FILE_TYPE = MACRO_DRAWING;
SET COLOR_WIRE YELLOW;
SET COLOR_PROP ORANGE;
SET COLOR_DOT WHITE;
SET COLOR_ARC YELLOW;
SET COLOR_BODY GREEN;
SET COLOR_NOTE PURPLE;
SET PROP_DISPLAY VALUE;
SET PAGE_NUMBER P113;
FORCEADD UNIVERSAL_GND..1
(-3675 75);
FORCEPROP 3 LASTPIN (-3675 125) SIG_NAME GND\g
J 0
(-3665 135);
DISPLAY 0.659574 (-3665 135);
PAINT MONO (-3665 135);
DISPLAY INVISIBLE (-3665 135);
FORCEPROP 1 LAST PATH I1
J 0
(-3600 75);
DISPLAY 0.872340 (-3600 75);
PAINT AQUA (-3600 75);
DISPLAY INVISIBLE (-3600 75);
FORCEPROP 1 LAST HDL_POWER GND
J 1
(-3650 0);
DISPLAY 0.872340 (-3650 0);
PAINT GREEN (-3650 0);
DISPLAY INVISIBLE (-3650 0);
FORCEPROP 2 LAST CDS_LIB logical_power
J 0
(-3675 75);
PAINT MONO (-3675 75);
DISPLAY INVISIBLE (-3675 75);
FORCEADD OFFPAGE..2
R 2
(-4825 1050);
FORCEPROP 2 LAST $XR0 58 
J 0
(-5079 1050);
DISPLAY 0.638298 (-5079 1050);
PAINT MONO (-5079 1050);
FORCEPROP 2 LAST CDS_LIB standard
J 0
(-4825 1050);
PAINT MONO (-4825 1050);
DISPLAY INVISIBLE (-4825 1050);
FORCEPROP 1 LAST OFFPAGE TRUE
J 2
(-5150 925);
DISPLAY 0.872340 (-5150 925);
DISPLAY INVISIBLE (-5150 925);
FORCEPROP 1 LAST COMMENT_BODY TRUE
J 2
(-4780 955);
DISPLAY 0.872340 (-4780 955);
PAINT GREEN (-4780 955);
DISPLAY INVISIBLE (-4780 955);
FORCEPROP 2 LAST PATH I10
J 0
(-4775 1125);
DISPLAY 1.021277 (-4775 1125);
DISPLAY INVISIBLE (-4775 1125);
FORCEADD TAP..1
(-2250 4050);
FORCEPROP 3 LASTPIN (-2300 4050) SIG_NAME M_H_CPU1_SA_DQ<23>
J 0
(-2290 4060);
DISPLAY 0.659574 (-2290 4060);
PAINT MONO (-2290 4060);
DISPLAY INVISIBLE (-2290 4060);
FORCEPROP 1 LASTPIN (-2300 4050) BN 23
J 0
(-2312 4058);
DISPLAY 0.680851 (-2312 4058);
PAINT GREEN (-2312 4058);
FORCEPROP 2 LAST CDS_LIB standard
J 0
(-2250 4050);
DISPLAY INVISIBLE (-2250 4050);
FORCEPROP 1 LAST BODY_TYPE PLUMBING
J 0
(-2250 4100);
DISPLAY 0.872340 (-2250 4100);
PAINT GREEN (-2250 4100);
DISPLAY INVISIBLE (-2250 4100);
FORCEPROP 1 LAST HDL_TAP TRUE
J 0
(-1925 3925);
DISPLAY 0.872340 (-1925 3925);
DISPLAY INVISIBLE (-1925 3925);
FORCEPROP 1 LAST PATH I100
J 0
(-2252 4050);
DISPLAY 0.872340 (-2252 4050);
PAINT GREEN (-2252 4050);
DISPLAY INVISIBLE (-2252 4050);
FORCEADD TAP..1
(-2250 4100);
FORCEPROP 3 LASTPIN (-2300 4100) SIG_NAME M_H_CPU1_SA_DQ<24>
J 0
(-2290 4110);
DISPLAY 0.659574 (-2290 4110);
PAINT MONO (-2290 4110);
DISPLAY INVISIBLE (-2290 4110);
FORCEPROP 1 LASTPIN (-2300 4100) BN 24
J 0
(-2312 4108);
DISPLAY 0.680851 (-2312 4108);
PAINT GREEN (-2312 4108);
FORCEPROP 2 LAST CDS_LIB standard
J 0
(-2250 4100);
DISPLAY INVISIBLE (-2250 4100);
FORCEPROP 1 LAST BODY_TYPE PLUMBING
J 0
(-2250 4150);
DISPLAY 0.872340 (-2250 4150);
PAINT GREEN (-2250 4150);
DISPLAY INVISIBLE (-2250 4150);
FORCEPROP 1 LAST HDL_TAP TRUE
J 0
(-1925 3975);
DISPLAY 0.872340 (-1925 3975);
DISPLAY INVISIBLE (-1925 3975);
FORCEPROP 1 LAST PATH I101
J 0
(-2252 4100);
DISPLAY 0.872340 (-2252 4100);
PAINT GREEN (-2252 4100);
DISPLAY INVISIBLE (-2252 4100);
FORCEADD TAP..1
(-2250 4000);
FORCEPROP 3 LASTPIN (-2300 4000) SIG_NAME M_H_CPU1_SA_DQ<22>
J 0
(-2290 4010);
DISPLAY 0.659574 (-2290 4010);
PAINT MONO (-2290 4010);
DISPLAY INVISIBLE (-2290 4010);
FORCEPROP 1 LASTPIN (-2300 4000) BN 22
J 0
(-2312 4008);
DISPLAY 0.680851 (-2312 4008);
PAINT GREEN (-2312 4008);
FORCEPROP 2 LAST CDS_LIB standard
J 0
(-2250 4000);
DISPLAY INVISIBLE (-2250 4000);
FORCEPROP 1 LAST BODY_TYPE PLUMBING
J 0
(-2250 4050);
DISPLAY 0.872340 (-2250 4050);
PAINT GREEN (-2250 4050);
DISPLAY INVISIBLE (-2250 4050);
FORCEPROP 1 LAST HDL_TAP TRUE
J 0
(-1925 3875);
DISPLAY 0.872340 (-1925 3875);
DISPLAY INVISIBLE (-1925 3875);
FORCEPROP 1 LAST PATH I102
J 0
(-2252 4000);
DISPLAY 0.872340 (-2252 4000);
PAINT GREEN (-2252 4000);
DISPLAY INVISIBLE (-2252 4000);
FORCEADD TAP..1
(-2250 3900);
FORCEPROP 3 LASTPIN (-2300 3900) SIG_NAME M_H_CPU1_SA_DQ<20>
J 0
(-2290 3910);
DISPLAY 0.659574 (-2290 3910);
PAINT MONO (-2290 3910);
DISPLAY INVISIBLE (-2290 3910);
FORCEPROP 1 LASTPIN (-2300 3900) BN 20
J 0
(-2312 3908);
DISPLAY 0.680851 (-2312 3908);
PAINT GREEN (-2312 3908);
FORCEPROP 2 LAST CDS_LIB standard
J 0
(-2250 3900);
PAINT MONO (-2250 3900);
DISPLAY INVISIBLE (-2250 3900);
FORCEPROP 1 LAST BODY_TYPE PLUMBING
J 0
(-2250 3950);
DISPLAY 0.872340 (-2250 3950);
PAINT GREEN (-2250 3950);
DISPLAY INVISIBLE (-2250 3950);
FORCEPROP 1 LAST HDL_TAP TRUE
J 0
(-1925 3775);
DISPLAY 0.872340 (-1925 3775);
DISPLAY INVISIBLE (-1925 3775);
FORCEPROP 1 LAST PATH I103
J 0
(-2252 3900);
DISPLAY 0.872340 (-2252 3900);
PAINT GREEN (-2252 3900);
DISPLAY INVISIBLE (-2252 3900);
FORCEADD TAP..1
(-2250 4300);
FORCEPROP 3 LASTPIN (-2300 4300) SIG_NAME M_H_CPU1_SA_DQ<28>
J 0
(-2290 4310);
DISPLAY 0.659574 (-2290 4310);
PAINT MONO (-2290 4310);
DISPLAY INVISIBLE (-2290 4310);
FORCEPROP 1 LASTPIN (-2300 4300) BN 28
J 0
(-2312 4308);
DISPLAY 0.680851 (-2312 4308);
PAINT GREEN (-2312 4308);
FORCEPROP 2 LAST CDS_LIB standard
J 0
(-2250 4300);
DISPLAY INVISIBLE (-2250 4300);
FORCEPROP 1 LAST BODY_TYPE PLUMBING
J 0
(-2250 4350);
DISPLAY 0.872340 (-2250 4350);
PAINT GREEN (-2250 4350);
DISPLAY INVISIBLE (-2250 4350);
FORCEPROP 1 LAST HDL_TAP TRUE
J 0
(-1925 4175);
DISPLAY 0.872340 (-1925 4175);
DISPLAY INVISIBLE (-1925 4175);
FORCEPROP 1 LAST PATH I104
J 0
(-2252 4300);
DISPLAY 0.872340 (-2252 4300);
PAINT GREEN (-2252 4300);
DISPLAY INVISIBLE (-2252 4300);
FORCEADD TAP..1
(-2250 4250);
FORCEPROP 3 LASTPIN (-2300 4250) SIG_NAME M_H_CPU1_SA_DQ<27>
J 0
(-2290 4260);
DISPLAY 0.659574 (-2290 4260);
PAINT MONO (-2290 4260);
DISPLAY INVISIBLE (-2290 4260);
FORCEPROP 1 LASTPIN (-2300 4250) BN 27
J 0
(-2312 4258);
DISPLAY 0.680851 (-2312 4258);
PAINT GREEN (-2312 4258);
FORCEPROP 2 LAST CDS_LIB standard
J 0
(-2250 4250);
DISPLAY INVISIBLE (-2250 4250);
FORCEPROP 1 LAST BODY_TYPE PLUMBING
J 0
(-2250 4300);
DISPLAY 0.872340 (-2250 4300);
PAINT GREEN (-2250 4300);
DISPLAY INVISIBLE (-2250 4300);
FORCEPROP 1 LAST HDL_TAP TRUE
J 0
(-1925 4125);
DISPLAY 0.872340 (-1925 4125);
DISPLAY INVISIBLE (-1925 4125);
FORCEPROP 1 LAST PATH I105
J 0
(-2252 4250);
DISPLAY 0.872340 (-2252 4250);
PAINT GREEN (-2252 4250);
DISPLAY INVISIBLE (-2252 4250);
FORCEADD TAP..1
(-2250 4350);
FORCEPROP 3 LASTPIN (-2300 4350) SIG_NAME M_H_CPU1_SA_DQ<29>
J 0
(-2290 4360);
DISPLAY 0.659574 (-2290 4360);
PAINT MONO (-2290 4360);
DISPLAY INVISIBLE (-2290 4360);
FORCEPROP 1 LASTPIN (-2300 4350) BN 29
J 0
(-2312 4358);
DISPLAY 0.680851 (-2312 4358);
PAINT GREEN (-2312 4358);
FORCEPROP 2 LAST CDS_LIB standard
J 0
(-2250 4350);
DISPLAY INVISIBLE (-2250 4350);
FORCEPROP 1 LAST BODY_TYPE PLUMBING
J 0
(-2250 4400);
DISPLAY 0.872340 (-2250 4400);
PAINT GREEN (-2250 4400);
DISPLAY INVISIBLE (-2250 4400);
FORCEPROP 1 LAST HDL_TAP TRUE
J 0
(-1925 4225);
DISPLAY 0.872340 (-1925 4225);
DISPLAY INVISIBLE (-1925 4225);
FORCEPROP 1 LAST PATH I106
J 0
(-2252 4350);
DISPLAY 0.872340 (-2252 4350);
PAINT GREEN (-2252 4350);
DISPLAY INVISIBLE (-2252 4350);
FORCEADD TAP..1
(-2250 4200);
FORCEPROP 3 LASTPIN (-2300 4200) SIG_NAME M_H_CPU1_SA_DQ<26>
J 0
(-2290 4210);
DISPLAY 0.659574 (-2290 4210);
PAINT MONO (-2290 4210);
DISPLAY INVISIBLE (-2290 4210);
FORCEPROP 1 LASTPIN (-2300 4200) BN 26
J 0
(-2312 4208);
DISPLAY 0.680851 (-2312 4208);
PAINT GREEN (-2312 4208);
FORCEPROP 2 LAST CDS_LIB standard
J 0
(-2250 4200);
DISPLAY INVISIBLE (-2250 4200);
FORCEPROP 1 LAST BODY_TYPE PLUMBING
J 0
(-2250 4250);
DISPLAY 0.872340 (-2250 4250);
PAINT GREEN (-2250 4250);
DISPLAY INVISIBLE (-2250 4250);
FORCEPROP 1 LAST HDL_TAP TRUE
J 0
(-1925 4075);
DISPLAY 0.872340 (-1925 4075);
DISPLAY INVISIBLE (-1925 4075);
FORCEPROP 1 LAST PATH I107
J 0
(-2252 4200);
DISPLAY 0.872340 (-2252 4200);
PAINT GREEN (-2252 4200);
DISPLAY INVISIBLE (-2252 4200);
FORCEADD TAP..1
(-2250 4150);
FORCEPROP 3 LASTPIN (-2300 4150) SIG_NAME M_H_CPU1_SA_DQ<25>
J 0
(-2290 4160);
DISPLAY 0.659574 (-2290 4160);
PAINT MONO (-2290 4160);
DISPLAY INVISIBLE (-2290 4160);
FORCEPROP 1 LASTPIN (-2300 4150) BN 25
J 0
(-2312 4158);
DISPLAY 0.680851 (-2312 4158);
PAINT GREEN (-2312 4158);
FORCEPROP 2 LAST CDS_LIB standard
J 0
(-2250 4150);
DISPLAY INVISIBLE (-2250 4150);
FORCEPROP 1 LAST BODY_TYPE PLUMBING
J 0
(-2250 4200);
DISPLAY 0.872340 (-2250 4200);
PAINT GREEN (-2250 4200);
DISPLAY INVISIBLE (-2250 4200);
FORCEPROP 1 LAST HDL_TAP TRUE
J 0
(-1925 4025);
DISPLAY 0.872340 (-1925 4025);
DISPLAY INVISIBLE (-1925 4025);
FORCEPROP 1 LAST PATH I108
J 0
(-2252 4150);
DISPLAY 0.872340 (-2252 4150);
PAINT GREEN (-2252 4150);
DISPLAY INVISIBLE (-2252 4150);
FORCEADD OFFPAGE..1
(-4825 4475);
FORCEPROP 2 LAST $XR1 112 
J 0
(-5166 4475);
DISPLAY 0.638298 (-5166 4475);
PAINT MONO (-5166 4475);
FORCEPROP 2 LAST $XR0 58 
J 0
(-5046 4475);
DISPLAY 0.638298 (-5046 4475);
PAINT MONO (-5046 4475);
FORCEPROP 2 LAST CDS_LIB standard
J 0
(-4825 4475);
PAINT MONO (-4825 4475);
DISPLAY INVISIBLE (-4825 4475);
FORCEPROP 1 LAST OFFPAGE TRUE
J 0
(-4500 4350);
DISPLAY 0.872340 (-4500 4350);
DISPLAY INVISIBLE (-4500 4350);
FORCEPROP 1 LAST COMMENT_BODY TRUE
J 0
(-4700 4375);
DISPLAY 0.872340 (-4700 4375);
PAINT GREEN (-4700 4375);
DISPLAY INVISIBLE (-4700 4375);
FORCEPROP 2 LAST PATH I109
J 0
(-4775 4550);
DISPLAY 1.021277 (-4775 4550);
DISPLAY INVISIBLE (-4775 4550);
FORCEADD OFFPAGE..2
R 2
(-4825 500);
FORCEPROP 2 LAST $XR0 113 
J 0
(-5110 500);
DISPLAY 0.638298 (-5110 500);
PAINT MONO (-5110 500);
FORCEPROP 2 LAST CDS_LIB standard
J 0
(-4825 500);
PAINT MONO (-4825 500);
DISPLAY INVISIBLE (-4825 500);
FORCEPROP 1 LAST OFFPAGE TRUE
J 2
(-5150 375);
DISPLAY 0.872340 (-5150 375);
DISPLAY INVISIBLE (-5150 375);
FORCEPROP 1 LAST COMMENT_BODY TRUE
J 2
(-4780 405);
DISPLAY 0.872340 (-4780 405);
PAINT GREEN (-4780 405);
DISPLAY INVISIBLE (-4780 405);
FORCEPROP 2 LAST PATH I11
J 0
(-4775 575);
DISPLAY 1.021277 (-4775 575);
DISPLAY INVISIBLE (-4775 575);
FORCEADD TAP..1
R 2
(-3900 4450);
FORCEPROP 3 LASTPIN (-3850 4450) SIG_NAME M_H_CPU1_SA_CA<6>
J 0
(-3840 4460);
DISPLAY 0.659574 (-3840 4460);
PAINT MONO (-3840 4460);
DISPLAY INVISIBLE (-3840 4460);
FORCEPROP 1 LASTPIN (-3850 4450) BN 6
J 2
(-3838 4458);
DISPLAY 0.680851 (-3838 4458);
PAINT GREEN (-3838 4458);
FORCEPROP 2 LAST CDS_LIB standard
J 0
(-3900 4450);
DISPLAY INVISIBLE (-3900 4450);
FORCEPROP 1 LAST BODY_TYPE PLUMBING
J 2
(-3900 4500);
DISPLAY 0.872340 (-3900 4500);
PAINT GREEN (-3900 4500);
DISPLAY INVISIBLE (-3900 4500);
FORCEPROP 1 LAST HDL_TAP TRUE
J 2
(-4225 4325);
DISPLAY 0.872340 (-4225 4325);
DISPLAY INVISIBLE (-4225 4325);
FORCEPROP 1 LAST PATH I110
J 2
(-3898 4450);
DISPLAY 0.872340 (-3898 4450);
PAINT GREEN (-3898 4450);
DISPLAY INVISIBLE (-3898 4450);
FORCEADD TAP..1
R 2
(-3900 4400);
FORCEPROP 3 LASTPIN (-3850 4400) SIG_NAME M_H_CPU1_SA_CA<5>
J 0
(-3840 4410);
DISPLAY 0.659574 (-3840 4410);
PAINT MONO (-3840 4410);
DISPLAY INVISIBLE (-3840 4410);
FORCEPROP 1 LASTPIN (-3850 4400) BN 5
J 2
(-3838 4408);
DISPLAY 0.680851 (-3838 4408);
PAINT GREEN (-3838 4408);
FORCEPROP 2 LAST CDS_LIB standard
J 0
(-3900 4400);
DISPLAY INVISIBLE (-3900 4400);
FORCEPROP 1 LAST BODY_TYPE PLUMBING
J 2
(-3900 4450);
DISPLAY 0.872340 (-3900 4450);
PAINT GREEN (-3900 4450);
DISPLAY INVISIBLE (-3900 4450);
FORCEPROP 1 LAST HDL_TAP TRUE
J 2
(-4225 4275);
DISPLAY 0.872340 (-4225 4275);
DISPLAY INVISIBLE (-4225 4275);
FORCEPROP 1 LAST PATH I111
J 2
(-3898 4400);
DISPLAY 0.872340 (-3898 4400);
PAINT GREEN (-3898 4400);
DISPLAY INVISIBLE (-3898 4400);
FORCEADD TAP..1
(-2250 4400);
FORCEPROP 3 LASTPIN (-2300 4400) SIG_NAME M_H_CPU1_SA_DQ<30>
J 0
(-2290 4410);
DISPLAY 0.659574 (-2290 4410);
PAINT MONO (-2290 4410);
DISPLAY INVISIBLE (-2290 4410);
FORCEPROP 1 LASTPIN (-2300 4400) BN 30
J 0
(-2312 4408);
DISPLAY 0.680851 (-2312 4408);
PAINT GREEN (-2312 4408);
FORCEPROP 2 LAST CDS_LIB standard
J 0
(-2250 4400);
DISPLAY INVISIBLE (-2250 4400);
FORCEPROP 1 LAST BODY_TYPE PLUMBING
J 0
(-2250 4450);
DISPLAY 0.872340 (-2250 4450);
PAINT GREEN (-2250 4450);
DISPLAY INVISIBLE (-2250 4450);
FORCEPROP 1 LAST HDL_TAP TRUE
J 0
(-1925 4275);
DISPLAY 0.872340 (-1925 4275);
DISPLAY INVISIBLE (-1925 4275);
FORCEPROP 1 LAST PATH I112
J 0
(-2252 4400);
DISPLAY 0.872340 (-2252 4400);
PAINT GREEN (-2252 4400);
DISPLAY INVISIBLE (-2252 4400);
FORCEADD TAP..1
(-2250 4450);
FORCEPROP 3 LASTPIN (-2300 4450) SIG_NAME M_H_CPU1_SA_DQ<31>
J 0
(-2290 4460);
DISPLAY 0.659574 (-2290 4460);
PAINT MONO (-2290 4460);
DISPLAY INVISIBLE (-2290 4460);
FORCEPROP 1 LASTPIN (-2300 4450) BN 31
J 0
(-2312 4458);
DISPLAY 0.680851 (-2312 4458);
PAINT GREEN (-2312 4458);
FORCEPROP 2 LAST CDS_LIB standard
J 0
(-2250 4450);
DISPLAY INVISIBLE (-2250 4450);
FORCEPROP 1 LAST BODY_TYPE PLUMBING
J 0
(-2250 4500);
DISPLAY 0.872340 (-2250 4500);
PAINT GREEN (-2250 4500);
DISPLAY INVISIBLE (-2250 4500);
FORCEPROP 1 LAST HDL_TAP TRUE
J 0
(-1925 4325);
DISPLAY 0.872340 (-1925 4325);
DISPLAY INVISIBLE (-1925 4325);
FORCEPROP 1 LAST PATH I113
J 0
(-2252 4450);
DISPLAY 0.872340 (-2252 4450);
PAINT GREEN (-2252 4450);
DISPLAY INVISIBLE (-2252 4450);
FORCEADD UNIVERSAL_GND..1
(-525 200);
FORCEPROP 3 LASTPIN (-525 250) SIG_NAME GND\g
J 0
(-515 260);
DISPLAY 0.659574 (-515 260);
PAINT MONO (-515 260);
DISPLAY INVISIBLE (-515 260);
FORCEPROP 1 LAST PATH I114
J 0
(-450 200);
DISPLAY 0.872340 (-450 200);
PAINT AQUA (-450 200);
DISPLAY INVISIBLE (-450 200);
FORCEPROP 1 LAST HDL_POWER GND
J 1
(-500 125);
DISPLAY 0.872340 (-500 125);
PAINT GREEN (-500 125);
DISPLAY INVISIBLE (-500 125);
FORCEPROP 2 LAST CDS_LIB logical_power
J 0
(-525 200);
PAINT MONO (-525 200);
DISPLAY INVISIBLE (-525 200);
FORCEADD UNIVERSAL_GND..1
(1100 200);
FORCEPROP 3 LASTPIN (1100 250) SIG_NAME GND\g
J 0
(1110 260);
DISPLAY 0.659574 (1110 260);
PAINT MONO (1110 260);
DISPLAY INVISIBLE (1110 260);
FORCEPROP 1 LAST PATH I115
J 0
(1175 200);
DISPLAY 0.872340 (1175 200);
PAINT AQUA (1175 200);
DISPLAY INVISIBLE (1175 200);
FORCEPROP 1 LAST HDL_POWER GND
J 1
(1125 125);
DISPLAY 0.872340 (1125 125);
PAINT GREEN (1125 125);
DISPLAY INVISIBLE (1125 125);
FORCEPROP 2 LAST CDS_LIB logical_power
J 0
(1100 200);
PAINT MONO (1100 200);
DISPLAY INVISIBLE (1100 200);
FORCEADD Q_CAP..1
(-525 575);
FORCEPROP 1 LAST PART_NUMBER CH5221MEB00
J 0
(-475 425);
DISPLAY 0.978723 (-475 425);
DISPLAY INVISIBLE (-475 425);
FORCEPROP 1 LAST VALUE 2.2UF
J 0
(-475 625);
DISPLAY 0.978723 (-475 625);
FORCEPROP 1 LAST PACK_TYPE C0402
J 0
(-475 375);
DISPLAY 0.978723 (-475 375);
FORCEPROP 1 LAST MATERIAL X6S
J 0
(-475 475);
DISPLAY 0.978723 (-475 475);
FORCEPROP 1 LAST TOLERANCE 20%
J 0
(-475 525);
DISPLAY 0.978723 (-475 525);
FORCEPROP 1 LAST VOLTAGE 6.3V
J 0
(-475 575);
DISPLAY 0.978723 (-475 575);
FORCEPROP 1 LAST $LOCATION C72
J 0
(-475 675);
DISPLAY 0.978723 (-475 675);
FORCEPROP 1 LASTPIN (-525 675) $PN 1
J 0
(-515 655);
DISPLAY 0.787234 (-515 655);
FORCEPROP 1 LASTPIN (-525 475) $PN 2
J 0
(-515 455);
DISPLAY 0.787234 (-515 455);
FORCEPROP 2 LAST CDS_LIB pure_quanta
J 0
(-525 575);
PAINT MONO (-525 575);
DISPLAY INVISIBLE (-525 575);
FORCEPROP 1 LAST PATH I116
J 0
(-475 725);
DISPLAY 0.978723 (-475 725);
PAINT WHITE (-475 725);
DISPLAY INVISIBLE (-475 725);
FORCEPROP 1 LAST $LOCATION C72
J 0
(-475 775);
DISPLAY 1.021277 (-475 775);
DISPLAY INVISIBLE (-475 775);
FORCEPROP 2 LAST CDS_LOCATION C72
J 0
(-475 775);
DISPLAY 1.021277 (-475 775);
DISPLAY INVISIBLE (-475 775);
FORCEPROP 2 LAST $SEC 1
J 0
(-475 775);
DISPLAY 0.680851 (-475 775);
PAINT MONO (-475 775);
DISPLAY INVISIBLE (-475 775);
FORCEPROP 2 LAST CDS_SEC 1
J 0
(-475 775);
DISPLAY 1.021277 (-475 775);
DISPLAY INVISIBLE (-475 775);
FORCEADD VCC_CORE..1
(-525 900);
FORCEPROP 3 LASTPIN (-525 850) SIG_NAME P3V3_AUX\g
J 0
(-515 860);
DISPLAY 0.659574 (-515 860);
PAINT MONO (-515 860);
DISPLAY INVISIBLE (-515 860);
FORCEPROP 1 LAST HDL_POWER P3V3_AUX
J 1
(-525 950);
DISPLAY 1.148936 (-525 950);
PAINT GREEN (-525 950);
FORCEPROP 2 LAST CDS_LIB logical_power
J 0
(-525 900);
PAINT MONO (-525 900);
DISPLAY INVISIBLE (-525 900);
FORCEPROP 1 LAST PATH I117
J 0
(-475 925);
DISPLAY 0.872340 (-475 925);
PAINT AQUA (-475 925);
DISPLAY INVISIBLE (-475 925);
FORCEADD OFFPAGE..3
(-1425 2825);
FORCEPROP 2 LAST $XR1 112 
J 0
(-1121 2825);
DISPLAY 0.638298 (-1121 2825);
PAINT MONO (-1121 2825);
FORCEPROP 2 LAST $XR0 58 
J 0
(-1211 2825);
DISPLAY 0.638298 (-1211 2825);
PAINT MONO (-1211 2825);
FORCEPROP 2 LAST CDS_LIB standard
J 2
(-1425 2825);
DISPLAY INVISIBLE (-1425 2825);
FORCEPROP 1 LAST OFFPAGE TRUE
J 0
(-1100 2700);
DISPLAY 0.872340 (-1100 2700);
DISPLAY INVISIBLE (-1100 2700);
FORCEPROP 1 LAST COMMENT_BODY TRUE
J 0
(-1475 2725);
DISPLAY 0.872340 (-1475 2725);
PAINT GREEN (-1475 2725);
DISPLAY INVISIBLE (-1475 2725);
FORCEPROP 2 LAST PATH I119
J 0
(-1225 2900);
DISPLAY 1.021277 (-1225 2900);
DISPLAY INVISIBLE (-1225 2900);
FORCEADD VCC_CORE..1
(-4725 2325);
FORCEPROP 3 LASTPIN (-4725 2275) SIG_NAME P3V3_AUX\g
J 0
(-4715 2285);
DISPLAY 0.659574 (-4715 2285);
PAINT MONO (-4715 2285);
DISPLAY INVISIBLE (-4715 2285);
FORCEPROP 1 LAST HDL_POWER P3V3_AUX
J 1
(-4725 2375);
DISPLAY 1.148936 (-4725 2375);
PAINT GREEN (-4725 2375);
FORCEPROP 2 LAST CDS_LIB logical_power
J 0
(-4725 2325);
PAINT MONO (-4725 2325);
DISPLAY INVISIBLE (-4725 2325);
FORCEPROP 1 LAST PATH I12
J 0
(-4675 2350);
DISPLAY 0.872340 (-4675 2350);
PAINT AQUA (-4675 2350);
DISPLAY INVISIBLE (-4675 2350);
FORCEADD Q_CAP..1
(475 575);
FORCEPROP 1 LAST PART_NUMBER CH6103KEA00
J 0
(525 425);
DISPLAY 0.978723 (525 425);
DISPLAY INVISIBLE (525 425);
FORCEPROP 1 LAST TOLERANCE 10%
J 0
(525 525);
DISPLAY 0.978723 (525 525);
FORCEPROP 1 LAST VOLTAGE 16V
J 0
(525 575);
DISPLAY 0.978723 (525 575);
FORCEPROP 1 LAST VALUE 10UF
J 0
(525 625);
DISPLAY 0.978723 (525 625);
FORCEPROP 1 LAST MATERIAL X6S
J 0
(525 475);
DISPLAY 0.978723 (525 475);
FORCEPROP 1 LAST PACK_TYPE C0805
J 0
(525 375);
DISPLAY 0.978723 (525 375);
FORCEPROP 1 LAST $LOCATION C73
J 0
(525 675);
DISPLAY 0.978723 (525 675);
FORCEPROP 1 LASTPIN (475 675) $PN 1
J 0
(485 655);
DISPLAY 0.787234 (485 655);
FORCEPROP 1 LASTPIN (475 475) $PN 2
J 0
(485 455);
DISPLAY 0.787234 (485 455);
FORCEPROP 2 LAST CDS_LIB pure_quanta
J 0
(475 575);
PAINT MONO (475 575);
DISPLAY INVISIBLE (475 575);
FORCEPROP 1 LAST PATH I120
J 0
(525 725);
DISPLAY 0.978723 (525 725);
PAINT WHITE (525 725);
DISPLAY INVISIBLE (525 725);
FORCEPROP 1 LAST $LOCATION C73
J 0
(525 775);
DISPLAY 1.021277 (525 775);
DISPLAY INVISIBLE (525 775);
FORCEPROP 2 LAST CDS_LOCATION C73
J 0
(525 775);
DISPLAY 1.021277 (525 775);
DISPLAY INVISIBLE (525 775);
FORCEPROP 2 LAST $SEC 1
J 0
(525 775);
DISPLAY 0.680851 (525 775);
PAINT MONO (525 775);
DISPLAY INVISIBLE (525 775);
FORCEPROP 2 LAST CDS_SEC 1
J 0
(525 775);
DISPLAY 1.021277 (525 775);
DISPLAY INVISIBLE (525 775);
FORCEADD VCC_CORE..1
(475 900);
FORCEPROP 3 LASTPIN (475 850) SIG_NAME P12V_S3_AUX_CPU1_NVDIMM\g
J 0
(485 860);
DISPLAY 0.659574 (485 860);
PAINT MONO (485 860);
DISPLAY INVISIBLE (485 860);
FORCEPROP 1 LAST HDL_POWER P12V_S3_AUX_CPU1_NVDIMM
J 1
(475 950);
DISPLAY 1.148936 (475 950);
PAINT GREEN (475 950);
FORCEPROP 2 LAST CDS_LIB logical_power
J 0
(475 900);
PAINT MONO (475 900);
DISPLAY INVISIBLE (475 900);
FORCEPROP 1 LAST PATH I121
J 0
(525 925);
DISPLAY 0.872340 (525 925);
PAINT AQUA (525 925);
DISPLAY INVISIBLE (525 925);
FORCEADD Q_CAP..1
(1100 575);
FORCEPROP 1 LAST PART_NUMBER CH6103KEA00
J 0
(1150 425);
DISPLAY 0.978723 (1150 425);
DISPLAY INVISIBLE (1150 425);
FORCEPROP 1 LAST MATERIAL X6S
J 0
(1150 475);
DISPLAY 0.978723 (1150 475);
FORCEPROP 1 LAST PACK_TYPE C0805
J 0
(1150 375);
DISPLAY 0.978723 (1150 375);
FORCEPROP 1 LAST VALUE 10UF
J 0
(1150 625);
DISPLAY 0.978723 (1150 625);
FORCEPROP 1 LAST VOLTAGE 16V
J 0
(1150 575);
DISPLAY 0.978723 (1150 575);
FORCEPROP 1 LAST TOLERANCE 10%
J 0
(1150 525);
DISPLAY 0.978723 (1150 525);
FORCEPROP 1 LAST $LOCATION C74
J 0
(1150 675);
DISPLAY 0.978723 (1150 675);
FORCEPROP 1 LASTPIN (1100 675) $PN 1
J 0
(1110 655);
DISPLAY 0.787234 (1110 655);
FORCEPROP 1 LASTPIN (1100 475) $PN 2
J 0
(1110 455);
DISPLAY 0.787234 (1110 455);
FORCEPROP 2 LAST CDS_LIB pure_quanta
J 0
(1100 575);
PAINT MONO (1100 575);
DISPLAY INVISIBLE (1100 575);
FORCEPROP 1 LAST PATH I122
J 0
(1150 725);
DISPLAY 0.978723 (1150 725);
PAINT WHITE (1150 725);
DISPLAY INVISIBLE (1150 725);
FORCEPROP 1 LAST $LOCATION C74
J 0
(1150 775);
DISPLAY 1.021277 (1150 775);
DISPLAY INVISIBLE (1150 775);
FORCEPROP 2 LAST CDS_LOCATION C74
J 0
(1150 775);
DISPLAY 1.021277 (1150 775);
DISPLAY INVISIBLE (1150 775);
FORCEPROP 2 LAST $SEC 1
J 0
(1150 775);
DISPLAY 0.680851 (1150 775);
PAINT MONO (1150 775);
DISPLAY INVISIBLE (1150 775);
FORCEPROP 2 LAST CDS_SEC 1
J 0
(1150 775);
DISPLAY 1.021277 (1150 775);
DISPLAY INVISIBLE (1150 775);
FORCEADD UNIVERSAL_GND..1
(2175 750);
FORCEPROP 3 LASTPIN (2175 800) SIG_NAME GND\g
J 0
(2185 810);
DISPLAY 0.659574 (2185 810);
PAINT MONO (2185 810);
DISPLAY INVISIBLE (2185 810);
FORCEPROP 1 LAST PATH I123
J 0
(2250 750);
DISPLAY 0.872340 (2250 750);
PAINT AQUA (2250 750);
DISPLAY INVISIBLE (2250 750);
FORCEPROP 1 LAST HDL_POWER GND
J 1
(2200 675);
DISPLAY 0.872340 (2200 675);
PAINT GREEN (2200 675);
DISPLAY INVISIBLE (2200 675);
FORCEPROP 2 LAST CDS_LIB logical_power
J 0
(2175 750);
PAINT MONO (2175 750);
DISPLAY INVISIBLE (2175 750);
FORCEADD TAP..1
(500 2500);
FORCEPROP 3 LASTPIN (450 2500) SIG_NAME M_H_CPU1_SB_DQS_DP<0>
J 0
(460 2510);
DISPLAY 0.659574 (460 2510);
PAINT MONO (460 2510);
DISPLAY INVISIBLE (460 2510);
FORCEPROP 1 LASTPIN (450 2500) BN 0
J 0
(438 2508);
DISPLAY 0.680851 (438 2508);
PAINT GREEN (438 2508);
FORCEPROP 2 LAST CDS_LIB standard
J 0
(500 2500);
PAINT MONO (500 2500);
DISPLAY INVISIBLE (500 2500);
FORCEPROP 1 LAST BODY_TYPE PLUMBING
J 0
(500 2550);
DISPLAY 0.872340 (500 2550);
PAINT GREEN (500 2550);
DISPLAY INVISIBLE (500 2550);
FORCEPROP 1 LAST HDL_TAP TRUE
J 0
(825 2375);
DISPLAY 0.872340 (825 2375);
DISPLAY INVISIBLE (825 2375);
FORCEPROP 1 LAST PATH I124
J 0
(498 2500);
DISPLAY 0.872340 (498 2500);
PAINT GREEN (498 2500);
DISPLAY INVISIBLE (498 2500);
FORCEADD TAP..1
(500 2800);
FORCEPROP 3 LASTPIN (450 2800) SIG_NAME M_H_CPU1_SB_DQS_DP<3>
J 0
(460 2810);
DISPLAY 0.659574 (460 2810);
PAINT MONO (460 2810);
DISPLAY INVISIBLE (460 2810);
FORCEPROP 1 LASTPIN (450 2800) BN 3
J 0
(438 2808);
DISPLAY 0.680851 (438 2808);
PAINT GREEN (438 2808);
FORCEPROP 2 LAST CDS_LIB standard
J 0
(500 2800);
PAINT MONO (500 2800);
DISPLAY INVISIBLE (500 2800);
FORCEPROP 1 LAST BODY_TYPE PLUMBING
J 0
(500 2850);
DISPLAY 0.872340 (500 2850);
PAINT GREEN (500 2850);
DISPLAY INVISIBLE (500 2850);
FORCEPROP 1 LAST HDL_TAP TRUE
J 0
(825 2675);
DISPLAY 0.872340 (825 2675);
DISPLAY INVISIBLE (825 2675);
FORCEPROP 1 LAST PATH I125
J 0
(498 2800);
DISPLAY 0.872340 (498 2800);
PAINT GREEN (498 2800);
DISPLAY INVISIBLE (498 2800);
FORCEADD TAP..1
(500 2700);
FORCEPROP 3 LASTPIN (450 2700) SIG_NAME M_H_CPU1_SB_DQS_DP<2>
J 0
(460 2710);
DISPLAY 0.659574 (460 2710);
PAINT MONO (460 2710);
DISPLAY INVISIBLE (460 2710);
FORCEPROP 1 LASTPIN (450 2700) BN 2
J 0
(438 2708);
DISPLAY 0.680851 (438 2708);
PAINT GREEN (438 2708);
FORCEPROP 2 LAST CDS_LIB standard
J 0
(500 2700);
DISPLAY INVISIBLE (500 2700);
FORCEPROP 1 LAST BODY_TYPE PLUMBING
J 0
(500 2750);
DISPLAY 0.872340 (500 2750);
PAINT GREEN (500 2750);
DISPLAY INVISIBLE (500 2750);
FORCEPROP 1 LAST HDL_TAP TRUE
J 0
(825 2575);
DISPLAY 0.872340 (825 2575);
DISPLAY INVISIBLE (825 2575);
FORCEPROP 1 LAST PATH I126
J 0
(498 2700);
DISPLAY 0.872340 (498 2700);
PAINT GREEN (498 2700);
DISPLAY INVISIBLE (498 2700);
FORCEADD TAP..1
(500 2600);
FORCEPROP 3 LASTPIN (450 2600) SIG_NAME M_H_CPU1_SB_DQS_DP<1>
J 0
(460 2610);
DISPLAY 0.659574 (460 2610);
PAINT MONO (460 2610);
DISPLAY INVISIBLE (460 2610);
FORCEPROP 1 LASTPIN (450 2600) BN 1
J 0
(438 2608);
DISPLAY 0.680851 (438 2608);
PAINT GREEN (438 2608);
FORCEPROP 2 LAST CDS_LIB standard
J 0
(500 2600);
DISPLAY INVISIBLE (500 2600);
FORCEPROP 1 LAST BODY_TYPE PLUMBING
J 0
(500 2650);
DISPLAY 0.872340 (500 2650);
PAINT GREEN (500 2650);
DISPLAY INVISIBLE (500 2650);
FORCEPROP 1 LAST HDL_TAP TRUE
J 0
(825 2475);
DISPLAY 0.872340 (825 2475);
DISPLAY INVISIBLE (825 2475);
FORCEPROP 1 LAST PATH I127
J 0
(498 2600);
DISPLAY 0.872340 (498 2600);
PAINT GREEN (498 2600);
DISPLAY INVISIBLE (498 2600);
FORCEADD TAP..1
(675 2550);
FORCEPROP 3 LASTPIN (625 2550) SIG_NAME M_H_CPU1_SB_DQS_DN<1>
J 0
(635 2560);
DISPLAY 0.659574 (635 2560);
PAINT MONO (635 2560);
DISPLAY INVISIBLE (635 2560);
FORCEPROP 1 LASTPIN (625 2550) BN 1
J 0
(613 2558);
DISPLAY 0.680851 (613 2558);
PAINT GREEN (613 2558);
FORCEPROP 2 LAST CDS_LIB standard
J 0
(675 2550);
DISPLAY INVISIBLE (675 2550);
FORCEPROP 1 LAST BODY_TYPE PLUMBING
J 0
(675 2600);
DISPLAY 0.872340 (675 2600);
PAINT GREEN (675 2600);
DISPLAY INVISIBLE (675 2600);
FORCEPROP 1 LAST HDL_TAP TRUE
J 0
(1000 2425);
DISPLAY 0.872340 (1000 2425);
DISPLAY INVISIBLE (1000 2425);
FORCEPROP 1 LAST PATH I128
J 0
(673 2550);
DISPLAY 0.872340 (673 2550);
PAINT GREEN (673 2550);
DISPLAY INVISIBLE (673 2550);
FORCEADD TAP..1
(675 2450);
FORCEPROP 3 LASTPIN (625 2450) SIG_NAME M_H_CPU1_SB_DQS_DN<0>
J 0
(635 2460);
DISPLAY 0.659574 (635 2460);
PAINT MONO (635 2460);
DISPLAY INVISIBLE (635 2460);
FORCEPROP 1 LASTPIN (625 2450) BN 0
J 0
(613 2458);
DISPLAY 0.680851 (613 2458);
PAINT GREEN (613 2458);
FORCEPROP 2 LAST CDS_LIB standard
J 0
(675 2450);
PAINT MONO (675 2450);
DISPLAY INVISIBLE (675 2450);
FORCEPROP 1 LAST BODY_TYPE PLUMBING
J 0
(675 2500);
DISPLAY 0.872340 (675 2500);
PAINT GREEN (675 2500);
DISPLAY INVISIBLE (675 2500);
FORCEPROP 1 LAST HDL_TAP TRUE
J 0
(1000 2325);
DISPLAY 0.872340 (1000 2325);
DISPLAY INVISIBLE (1000 2325);
FORCEPROP 1 LAST PATH I129
J 0
(673 2450);
DISPLAY 0.872340 (673 2450);
PAINT GREEN (673 2450);
DISPLAY INVISIBLE (673 2450);
FORCEADD TAP..1
R 2
(-3900 2250);
FORCEPROP 3 LASTPIN (-3850 2250) SIG_NAME M_H_CPU1_SB_CB<0>
J 0
(-3840 2260);
DISPLAY 0.659574 (-3840 2260);
PAINT MONO (-3840 2260);
DISPLAY INVISIBLE (-3840 2260);
FORCEPROP 1 LASTPIN (-3850 2250) BN 0
J 2
(-3838 2258);
DISPLAY 0.680851 (-3838 2258);
PAINT GREEN (-3838 2258);
FORCEPROP 2 LAST CDS_LIB standard
J 0
(-3900 2250);
PAINT MONO (-3900 2250);
DISPLAY INVISIBLE (-3900 2250);
FORCEPROP 1 LAST BODY_TYPE PLUMBING
J 2
(-3900 2300);
DISPLAY 0.872340 (-3900 2300);
PAINT GREEN (-3900 2300);
DISPLAY INVISIBLE (-3900 2300);
FORCEPROP 1 LAST HDL_TAP TRUE
J 2
(-4225 2125);
DISPLAY 0.872340 (-4225 2125);
DISPLAY INVISIBLE (-4225 2125);
FORCEPROP 1 LAST PATH I13
J 2
(-3898 2250);
DISPLAY 0.872340 (-3898 2250);
PAINT GREEN (-3898 2250);
DISPLAY INVISIBLE (-3898 2250);
FORCEADD TAP..1
(675 2650);
FORCEPROP 3 LASTPIN (625 2650) SIG_NAME M_H_CPU1_SB_DQS_DN<2>
J 0
(635 2660);
DISPLAY 0.659574 (635 2660);
PAINT MONO (635 2660);
DISPLAY INVISIBLE (635 2660);
FORCEPROP 1 LASTPIN (625 2650) BN 2
J 0
(613 2658);
DISPLAY 0.680851 (613 2658);
PAINT GREEN (613 2658);
FORCEPROP 2 LAST CDS_LIB standard
J 0
(675 2650);
DISPLAY INVISIBLE (675 2650);
FORCEPROP 1 LAST BODY_TYPE PLUMBING
J 0
(675 2700);
DISPLAY 0.872340 (675 2700);
PAINT GREEN (675 2700);
DISPLAY INVISIBLE (675 2700);
FORCEPROP 1 LAST HDL_TAP TRUE
J 0
(1000 2525);
DISPLAY 0.872340 (1000 2525);
DISPLAY INVISIBLE (1000 2525);
FORCEPROP 1 LAST PATH I130
J 0
(673 2650);
DISPLAY 0.872340 (673 2650);
PAINT GREEN (673 2650);
DISPLAY INVISIBLE (673 2650);
FORCEADD TAP..1
(675 2750);
FORCEPROP 3 LASTPIN (625 2750) SIG_NAME M_H_CPU1_SB_DQS_DN<3>
J 0
(635 2760);
DISPLAY 0.659574 (635 2760);
PAINT MONO (635 2760);
DISPLAY INVISIBLE (635 2760);
FORCEPROP 1 LASTPIN (625 2750) BN 3
J 0
(613 2758);
DISPLAY 0.680851 (613 2758);
PAINT GREEN (613 2758);
FORCEPROP 2 LAST CDS_LIB standard
J 0
(675 2750);
PAINT MONO (675 2750);
DISPLAY INVISIBLE (675 2750);
FORCEPROP 1 LAST BODY_TYPE PLUMBING
J 0
(675 2800);
DISPLAY 0.872340 (675 2800);
PAINT GREEN (675 2800);
DISPLAY INVISIBLE (675 2800);
FORCEPROP 1 LAST HDL_TAP TRUE
J 0
(1000 2625);
DISPLAY 0.872340 (1000 2625);
DISPLAY INVISIBLE (1000 2625);
FORCEPROP 1 LAST PATH I131
J 0
(673 2750);
DISPLAY 0.872340 (673 2750);
PAINT GREEN (673 2750);
DISPLAY INVISIBLE (673 2750);
FORCEADD TAP..1
(500 3000);
FORCEPROP 3 LASTPIN (450 3000) SIG_NAME M_H_CPU1_SB_DQS_DP<5>
J 0
(460 3010);
DISPLAY 0.659574 (460 3010);
PAINT MONO (460 3010);
DISPLAY INVISIBLE (460 3010);
FORCEPROP 1 LASTPIN (450 3000) BN 5
J 0
(438 3008);
DISPLAY 0.680851 (438 3008);
PAINT GREEN (438 3008);
FORCEPROP 2 LAST CDS_LIB standard
J 0
(500 3000);
DISPLAY INVISIBLE (500 3000);
FORCEPROP 1 LAST BODY_TYPE PLUMBING
J 0
(500 3050);
DISPLAY 0.872340 (500 3050);
PAINT GREEN (500 3050);
DISPLAY INVISIBLE (500 3050);
FORCEPROP 1 LAST HDL_TAP TRUE
J 0
(825 2875);
DISPLAY 0.872340 (825 2875);
DISPLAY INVISIBLE (825 2875);
FORCEPROP 1 LAST PATH I132
J 0
(498 3000);
DISPLAY 0.872340 (498 3000);
PAINT GREEN (498 3000);
DISPLAY INVISIBLE (498 3000);
FORCEADD TAP..1
(500 2900);
FORCEPROP 3 LASTPIN (450 2900) SIG_NAME M_H_CPU1_SB_DQS_DP<4>
J 0
(460 2910);
DISPLAY 0.659574 (460 2910);
PAINT MONO (460 2910);
DISPLAY INVISIBLE (460 2910);
FORCEPROP 1 LASTPIN (450 2900) BN 4
J 0
(438 2908);
DISPLAY 0.680851 (438 2908);
PAINT GREEN (438 2908);
FORCEPROP 2 LAST CDS_LIB standard
J 0
(500 2900);
PAINT MONO (500 2900);
DISPLAY INVISIBLE (500 2900);
FORCEPROP 1 LAST BODY_TYPE PLUMBING
J 0
(500 2950);
DISPLAY 0.872340 (500 2950);
PAINT GREEN (500 2950);
DISPLAY INVISIBLE (500 2950);
FORCEPROP 1 LAST HDL_TAP TRUE
J 0
(825 2775);
DISPLAY 0.872340 (825 2775);
DISPLAY INVISIBLE (825 2775);
FORCEPROP 1 LAST PATH I133
J 0
(498 2900);
DISPLAY 0.872340 (498 2900);
PAINT GREEN (498 2900);
DISPLAY INVISIBLE (498 2900);
FORCEADD TAP..1
(500 3300);
FORCEPROP 3 LASTPIN (450 3300) SIG_NAME M_H_CPU1_SB_DQS_DP<8>
J 0
(460 3310);
DISPLAY 0.659574 (460 3310);
PAINT MONO (460 3310);
DISPLAY INVISIBLE (460 3310);
FORCEPROP 1 LASTPIN (450 3300) BN 8
J 0
(438 3308);
DISPLAY 0.680851 (438 3308);
PAINT GREEN (438 3308);
FORCEPROP 2 LAST CDS_LIB standard
J 0
(500 3300);
DISPLAY INVISIBLE (500 3300);
FORCEPROP 1 LAST BODY_TYPE PLUMBING
J 0
(500 3350);
DISPLAY 0.872340 (500 3350);
PAINT GREEN (500 3350);
DISPLAY INVISIBLE (500 3350);
FORCEPROP 1 LAST HDL_TAP TRUE
J 0
(825 3175);
DISPLAY 0.872340 (825 3175);
DISPLAY INVISIBLE (825 3175);
FORCEPROP 1 LAST PATH I134
J 0
(498 3300);
DISPLAY 0.872340 (498 3300);
PAINT GREEN (498 3300);
DISPLAY INVISIBLE (498 3300);
FORCEADD TAP..1
(500 3200);
FORCEPROP 3 LASTPIN (450 3200) SIG_NAME M_H_CPU1_SB_DQS_DP<7>
J 0
(460 3210);
DISPLAY 0.659574 (460 3210);
PAINT MONO (460 3210);
DISPLAY INVISIBLE (460 3210);
FORCEPROP 1 LASTPIN (450 3200) BN 7
J 0
(438 3208);
DISPLAY 0.680851 (438 3208);
PAINT GREEN (438 3208);
FORCEPROP 2 LAST CDS_LIB standard
J 0
(500 3200);
DISPLAY INVISIBLE (500 3200);
FORCEPROP 1 LAST BODY_TYPE PLUMBING
J 0
(500 3250);
DISPLAY 0.872340 (500 3250);
PAINT GREEN (500 3250);
DISPLAY INVISIBLE (500 3250);
FORCEPROP 1 LAST HDL_TAP TRUE
J 0
(825 3075);
DISPLAY 0.872340 (825 3075);
DISPLAY INVISIBLE (825 3075);
FORCEPROP 1 LAST PATH I135
J 0
(498 3200);
DISPLAY 0.872340 (498 3200);
PAINT GREEN (498 3200);
DISPLAY INVISIBLE (498 3200);
FORCEADD TAP..1
(500 3100);
FORCEPROP 3 LASTPIN (450 3100) SIG_NAME M_H_CPU1_SB_DQS_DP<6>
J 0
(460 3110);
DISPLAY 0.659574 (460 3110);
PAINT MONO (460 3110);
DISPLAY INVISIBLE (460 3110);
FORCEPROP 1 LASTPIN (450 3100) BN 6
J 0
(438 3108);
DISPLAY 0.680851 (438 3108);
PAINT GREEN (438 3108);
FORCEPROP 2 LAST CDS_LIB standard
J 0
(500 3100);
DISPLAY INVISIBLE (500 3100);
FORCEPROP 1 LAST BODY_TYPE PLUMBING
J 0
(500 3150);
DISPLAY 0.872340 (500 3150);
PAINT GREEN (500 3150);
DISPLAY INVISIBLE (500 3150);
FORCEPROP 1 LAST HDL_TAP TRUE
J 0
(825 2975);
DISPLAY 0.872340 (825 2975);
DISPLAY INVISIBLE (825 2975);
FORCEPROP 1 LAST PATH I136
J 0
(498 3100);
DISPLAY 0.872340 (498 3100);
PAINT GREEN (498 3100);
DISPLAY INVISIBLE (498 3100);
FORCEADD TAP..1
(675 2950);
FORCEPROP 3 LASTPIN (625 2950) SIG_NAME M_H_CPU1_SB_DQS_DN<5>
J 0
(635 2960);
DISPLAY 0.659574 (635 2960);
PAINT MONO (635 2960);
DISPLAY INVISIBLE (635 2960);
FORCEPROP 1 LASTPIN (625 2950) BN 5
J 0
(613 2958);
DISPLAY 0.680851 (613 2958);
PAINT GREEN (613 2958);
FORCEPROP 2 LAST CDS_LIB standard
J 0
(675 2950);
DISPLAY INVISIBLE (675 2950);
FORCEPROP 1 LAST BODY_TYPE PLUMBING
J 0
(675 3000);
DISPLAY 0.872340 (675 3000);
PAINT GREEN (675 3000);
DISPLAY INVISIBLE (675 3000);
FORCEPROP 1 LAST HDL_TAP TRUE
J 0
(1000 2825);
DISPLAY 0.872340 (1000 2825);
DISPLAY INVISIBLE (1000 2825);
FORCEPROP 1 LAST PATH I137
J 0
(673 2950);
DISPLAY 0.872340 (673 2950);
PAINT GREEN (673 2950);
DISPLAY INVISIBLE (673 2950);
FORCEADD TAP..1
(675 2850);
FORCEPROP 3 LASTPIN (625 2850) SIG_NAME M_H_CPU1_SB_DQS_DN<4>
J 0
(635 2860);
DISPLAY 0.659574 (635 2860);
PAINT MONO (635 2860);
DISPLAY INVISIBLE (635 2860);
FORCEPROP 1 LASTPIN (625 2850) BN 4
J 0
(613 2858);
DISPLAY 0.680851 (613 2858);
PAINT GREEN (613 2858);
FORCEPROP 2 LAST CDS_LIB standard
J 0
(675 2850);
PAINT MONO (675 2850);
DISPLAY INVISIBLE (675 2850);
FORCEPROP 1 LAST BODY_TYPE PLUMBING
J 0
(675 2900);
DISPLAY 0.872340 (675 2900);
PAINT GREEN (675 2900);
DISPLAY INVISIBLE (675 2900);
FORCEPROP 1 LAST HDL_TAP TRUE
J 0
(1000 2725);
DISPLAY 0.872340 (1000 2725);
DISPLAY INVISIBLE (1000 2725);
FORCEPROP 1 LAST PATH I138
J 0
(673 2850);
DISPLAY 0.872340 (673 2850);
PAINT GREEN (673 2850);
DISPLAY INVISIBLE (673 2850);
FORCEADD TAP..1
(675 3050);
FORCEPROP 3 LASTPIN (625 3050) SIG_NAME M_H_CPU1_SB_DQS_DN<6>
J 0
(635 3060);
DISPLAY 0.659574 (635 3060);
PAINT MONO (635 3060);
DISPLAY INVISIBLE (635 3060);
FORCEPROP 1 LASTPIN (625 3050) BN 6
J 0
(613 3058);
DISPLAY 0.680851 (613 3058);
PAINT GREEN (613 3058);
FORCEPROP 2 LAST CDS_LIB standard
J 0
(675 3050);
DISPLAY INVISIBLE (675 3050);
FORCEPROP 1 LAST BODY_TYPE PLUMBING
J 0
(675 3100);
DISPLAY 0.872340 (675 3100);
PAINT GREEN (675 3100);
DISPLAY INVISIBLE (675 3100);
FORCEPROP 1 LAST HDL_TAP TRUE
J 0
(1000 2925);
DISPLAY 0.872340 (1000 2925);
DISPLAY INVISIBLE (1000 2925);
FORCEPROP 1 LAST PATH I139
J 0
(673 3050);
DISPLAY 0.872340 (673 3050);
PAINT GREEN (673 3050);
DISPLAY INVISIBLE (673 3050);
FORCEADD OFFPAGE..3
R 2
(-4825 2625);
FORCEPROP 2 LAST $XR1 112 
J 0
(-5194 2625);
DISPLAY 0.638298 (-5194 2625);
PAINT MONO (-5194 2625);
FORCEPROP 2 LAST $XR0 58 
J 0
(-5074 2625);
DISPLAY 0.638298 (-5074 2625);
PAINT MONO (-5074 2625);
FORCEPROP 2 LAST CDS_LIB standard
J 0
(-4825 2625);
PAINT MONO (-4825 2625);
DISPLAY INVISIBLE (-4825 2625);
FORCEPROP 1 LAST OFFPAGE TRUE
J 2
(-5150 2500);
DISPLAY 0.872340 (-5150 2500);
DISPLAY INVISIBLE (-5150 2500);
FORCEPROP 1 LAST COMMENT_BODY TRUE
J 2
(-4775 2525);
DISPLAY 0.872340 (-4775 2525);
PAINT GREEN (-4775 2525);
DISPLAY INVISIBLE (-4775 2525);
FORCEPROP 2 LAST PATH I14
J 0
(-4775 2700);
DISPLAY 1.021277 (-4775 2700);
DISPLAY INVISIBLE (-4775 2700);
FORCEADD TAP..1
(675 3150);
FORCEPROP 3 LASTPIN (625 3150) SIG_NAME M_H_CPU1_SB_DQS_DN<7>
J 0
(635 3160);
DISPLAY 0.659574 (635 3160);
PAINT MONO (635 3160);
DISPLAY INVISIBLE (635 3160);
FORCEPROP 1 LASTPIN (625 3150) BN 7
J 0
(613 3158);
DISPLAY 0.680851 (613 3158);
PAINT GREEN (613 3158);
FORCEPROP 2 LAST CDS_LIB standard
J 0
(675 3150);
DISPLAY INVISIBLE (675 3150);
FORCEPROP 1 LAST BODY_TYPE PLUMBING
J 0
(675 3200);
DISPLAY 0.872340 (675 3200);
PAINT GREEN (675 3200);
DISPLAY INVISIBLE (675 3200);
FORCEPROP 1 LAST HDL_TAP TRUE
J 0
(1000 3025);
DISPLAY 0.872340 (1000 3025);
DISPLAY INVISIBLE (1000 3025);
FORCEPROP 1 LAST PATH I140
J 0
(673 3150);
DISPLAY 0.872340 (673 3150);
PAINT GREEN (673 3150);
DISPLAY INVISIBLE (673 3150);
FORCEADD TAP..1
(675 3250);
FORCEPROP 3 LASTPIN (625 3250) SIG_NAME M_H_CPU1_SB_DQS_DN<8>
J 0
(635 3260);
DISPLAY 0.659574 (635 3260);
PAINT MONO (635 3260);
DISPLAY INVISIBLE (635 3260);
FORCEPROP 1 LASTPIN (625 3250) BN 8
J 0
(613 3258);
DISPLAY 0.680851 (613 3258);
PAINT GREEN (613 3258);
FORCEPROP 2 LAST CDS_LIB standard
J 0
(675 3250);
DISPLAY INVISIBLE (675 3250);
FORCEPROP 1 LAST BODY_TYPE PLUMBING
J 0
(675 3300);
DISPLAY 0.872340 (675 3300);
PAINT GREEN (675 3300);
DISPLAY INVISIBLE (675 3300);
FORCEPROP 1 LAST HDL_TAP TRUE
J 0
(1000 3125);
DISPLAY 0.872340 (1000 3125);
DISPLAY INVISIBLE (1000 3125);
FORCEPROP 1 LAST PATH I141
J 0
(673 3250);
DISPLAY 0.872340 (673 3250);
PAINT GREEN (673 3250);
DISPLAY INVISIBLE (673 3250);
FORCEADD TAP..1
(500 3550);
FORCEPROP 3 LASTPIN (450 3550) SIG_NAME M_H_CPU1_SA_DQS_DP<0>
J 0
(460 3560);
DISPLAY 0.659574 (460 3560);
PAINT MONO (460 3560);
DISPLAY INVISIBLE (460 3560);
FORCEPROP 1 LASTPIN (450 3550) BN 0
J 0
(438 3558);
DISPLAY 0.680851 (438 3558);
PAINT GREEN (438 3558);
FORCEPROP 2 LAST CDS_LIB standard
J 0
(500 3550);
PAINT MONO (500 3550);
DISPLAY INVISIBLE (500 3550);
FORCEPROP 1 LAST BODY_TYPE PLUMBING
J 0
(500 3600);
DISPLAY 0.872340 (500 3600);
PAINT GREEN (500 3600);
DISPLAY INVISIBLE (500 3600);
FORCEPROP 1 LAST HDL_TAP TRUE
J 0
(825 3425);
DISPLAY 0.872340 (825 3425);
DISPLAY INVISIBLE (825 3425);
FORCEPROP 1 LAST PATH I142
J 0
(498 3550);
DISPLAY 0.872340 (498 3550);
PAINT GREEN (498 3550);
DISPLAY INVISIBLE (498 3550);
FORCEADD TAP..1
(500 3400);
FORCEPROP 3 LASTPIN (450 3400) SIG_NAME M_H_CPU1_SB_DQS_DP<9>
J 0
(460 3410);
DISPLAY 0.659574 (460 3410);
PAINT MONO (460 3410);
DISPLAY INVISIBLE (460 3410);
FORCEPROP 1 LASTPIN (450 3400) BN 9
J 0
(438 3408);
DISPLAY 0.680851 (438 3408);
PAINT GREEN (438 3408);
FORCEPROP 2 LAST CDS_LIB standard
J 0
(500 3400);
DISPLAY INVISIBLE (500 3400);
FORCEPROP 1 LAST BODY_TYPE PLUMBING
J 0
(500 3450);
DISPLAY 0.872340 (500 3450);
PAINT GREEN (500 3450);
DISPLAY INVISIBLE (500 3450);
FORCEPROP 1 LAST HDL_TAP TRUE
J 0
(825 3275);
DISPLAY 0.872340 (825 3275);
DISPLAY INVISIBLE (825 3275);
FORCEPROP 1 LAST PATH I143
J 0
(498 3400);
DISPLAY 0.872340 (498 3400);
PAINT GREEN (498 3400);
DISPLAY INVISIBLE (498 3400);
FORCEADD TAP..1
(500 3850);
FORCEPROP 3 LASTPIN (450 3850) SIG_NAME M_H_CPU1_SA_DQS_DP<3>
J 0
(460 3860);
DISPLAY 0.659574 (460 3860);
PAINT MONO (460 3860);
DISPLAY INVISIBLE (460 3860);
FORCEPROP 1 LASTPIN (450 3850) BN 3
J 0
(438 3858);
DISPLAY 0.680851 (438 3858);
PAINT GREEN (438 3858);
FORCEPROP 2 LAST CDS_LIB standard
J 0
(500 3850);
PAINT MONO (500 3850);
DISPLAY INVISIBLE (500 3850);
FORCEPROP 1 LAST BODY_TYPE PLUMBING
J 0
(500 3900);
DISPLAY 0.872340 (500 3900);
PAINT GREEN (500 3900);
DISPLAY INVISIBLE (500 3900);
FORCEPROP 1 LAST HDL_TAP TRUE
J 0
(825 3725);
DISPLAY 0.872340 (825 3725);
DISPLAY INVISIBLE (825 3725);
FORCEPROP 1 LAST PATH I144
J 0
(498 3850);
DISPLAY 0.872340 (498 3850);
PAINT GREEN (498 3850);
DISPLAY INVISIBLE (498 3850);
FORCEADD TAP..1
(500 3750);
FORCEPROP 3 LASTPIN (450 3750) SIG_NAME M_H_CPU1_SA_DQS_DP<2>
J 0
(460 3760);
DISPLAY 0.659574 (460 3760);
PAINT MONO (460 3760);
DISPLAY INVISIBLE (460 3760);
FORCEPROP 1 LASTPIN (450 3750) BN 2
J 0
(438 3758);
DISPLAY 0.680851 (438 3758);
PAINT GREEN (438 3758);
FORCEPROP 2 LAST CDS_LIB standard
J 0
(500 3750);
DISPLAY INVISIBLE (500 3750);
FORCEPROP 1 LAST BODY_TYPE PLUMBING
J 0
(500 3800);
DISPLAY 0.872340 (500 3800);
PAINT GREEN (500 3800);
DISPLAY INVISIBLE (500 3800);
FORCEPROP 1 LAST HDL_TAP TRUE
J 0
(825 3625);
DISPLAY 0.872340 (825 3625);
DISPLAY INVISIBLE (825 3625);
FORCEPROP 1 LAST PATH I145
J 0
(498 3750);
DISPLAY 0.872340 (498 3750);
PAINT GREEN (498 3750);
DISPLAY INVISIBLE (498 3750);
FORCEADD TAP..1
(500 3650);
FORCEPROP 3 LASTPIN (450 3650) SIG_NAME M_H_CPU1_SA_DQS_DP<1>
J 0
(460 3660);
DISPLAY 0.659574 (460 3660);
PAINT MONO (460 3660);
DISPLAY INVISIBLE (460 3660);
FORCEPROP 1 LASTPIN (450 3650) BN 1
J 0
(438 3658);
DISPLAY 0.680851 (438 3658);
PAINT GREEN (438 3658);
FORCEPROP 2 LAST CDS_LIB standard
J 0
(500 3650);
DISPLAY INVISIBLE (500 3650);
FORCEPROP 1 LAST BODY_TYPE PLUMBING
J 0
(500 3700);
DISPLAY 0.872340 (500 3700);
PAINT GREEN (500 3700);
DISPLAY INVISIBLE (500 3700);
FORCEPROP 1 LAST HDL_TAP TRUE
J 0
(825 3525);
DISPLAY 0.872340 (825 3525);
DISPLAY INVISIBLE (825 3525);
FORCEPROP 1 LAST PATH I146
J 0
(498 3650);
DISPLAY 0.872340 (498 3650);
PAINT GREEN (498 3650);
DISPLAY INVISIBLE (498 3650);
FORCEADD TAP..1
(675 3350);
FORCEPROP 3 LASTPIN (625 3350) SIG_NAME M_H_CPU1_SB_DQS_DN<9>
J 0
(635 3360);
DISPLAY 0.659574 (635 3360);
PAINT MONO (635 3360);
DISPLAY INVISIBLE (635 3360);
FORCEPROP 1 LASTPIN (625 3350) BN 9
J 0
(613 3358);
DISPLAY 0.680851 (613 3358);
PAINT GREEN (613 3358);
FORCEPROP 2 LAST CDS_LIB standard
J 0
(675 3350);
DISPLAY INVISIBLE (675 3350);
FORCEPROP 1 LAST BODY_TYPE PLUMBING
J 0
(675 3400);
DISPLAY 0.872340 (675 3400);
PAINT GREEN (675 3400);
DISPLAY INVISIBLE (675 3400);
FORCEPROP 1 LAST HDL_TAP TRUE
J 0
(1000 3225);
DISPLAY 0.872340 (1000 3225);
DISPLAY INVISIBLE (1000 3225);
FORCEPROP 1 LAST PATH I147
J 0
(673 3350);
DISPLAY 0.872340 (673 3350);
PAINT GREEN (673 3350);
DISPLAY INVISIBLE (673 3350);
FORCEADD TAP..1
(675 3600);
FORCEPROP 3 LASTPIN (625 3600) SIG_NAME M_H_CPU1_SA_DQS_DN<1>
J 0
(635 3610);
DISPLAY 0.659574 (635 3610);
PAINT MONO (635 3610);
DISPLAY INVISIBLE (635 3610);
FORCEPROP 1 LASTPIN (625 3600) BN 1
J 0
(613 3608);
DISPLAY 0.680851 (613 3608);
PAINT GREEN (613 3608);
FORCEPROP 2 LAST CDS_LIB standard
J 0
(675 3600);
DISPLAY INVISIBLE (675 3600);
FORCEPROP 1 LAST BODY_TYPE PLUMBING
J 0
(675 3650);
DISPLAY 0.872340 (675 3650);
PAINT GREEN (675 3650);
DISPLAY INVISIBLE (675 3650);
FORCEPROP 1 LAST HDL_TAP TRUE
J 0
(1000 3475);
DISPLAY 0.872340 (1000 3475);
DISPLAY INVISIBLE (1000 3475);
FORCEPROP 1 LAST PATH I148
J 0
(673 3600);
DISPLAY 0.872340 (673 3600);
PAINT GREEN (673 3600);
DISPLAY INVISIBLE (673 3600);
FORCEADD TAP..1
(675 3500);
FORCEPROP 3 LASTPIN (625 3500) SIG_NAME M_H_CPU1_SA_DQS_DN<0>
J 0
(635 3510);
DISPLAY 0.659574 (635 3510);
PAINT MONO (635 3510);
DISPLAY INVISIBLE (635 3510);
FORCEPROP 1 LASTPIN (625 3500) BN 0
J 0
(613 3508);
DISPLAY 0.680851 (613 3508);
PAINT GREEN (613 3508);
FORCEPROP 2 LAST CDS_LIB standard
J 0
(675 3500);
PAINT MONO (675 3500);
DISPLAY INVISIBLE (675 3500);
FORCEPROP 1 LAST BODY_TYPE PLUMBING
J 0
(675 3550);
DISPLAY 0.872340 (675 3550);
PAINT GREEN (675 3550);
DISPLAY INVISIBLE (675 3550);
FORCEPROP 1 LAST HDL_TAP TRUE
J 0
(1000 3375);
DISPLAY 0.872340 (1000 3375);
DISPLAY INVISIBLE (1000 3375);
FORCEPROP 1 LAST PATH I149
J 0
(673 3500);
DISPLAY 0.872340 (673 3500);
PAINT GREEN (673 3500);
DISPLAY INVISIBLE (673 3500);
FORCEADD OFFPAGE..1
(-4825 3300);
FORCEPROP 2 LAST $XR0 58 
J 0
(-5046 3300);
DISPLAY 0.638298 (-5046 3300);
PAINT MONO (-5046 3300);
FORCEPROP 2 LAST CDS_LIB standard
J 0
(-4825 3300);
PAINT MONO (-4825 3300);
DISPLAY INVISIBLE (-4825 3300);
FORCEPROP 1 LAST OFFPAGE TRUE
J 0
(-4500 3175);
DISPLAY 0.872340 (-4500 3175);
DISPLAY INVISIBLE (-4500 3175);
FORCEPROP 1 LAST COMMENT_BODY TRUE
J 0
(-4700 3200);
DISPLAY 0.872340 (-4700 3200);
PAINT GREEN (-4700 3200);
DISPLAY INVISIBLE (-4700 3200);
FORCEPROP 2 LAST PATH I15
J 0
(-4775 3375);
DISPLAY 1.021277 (-4775 3375);
DISPLAY INVISIBLE (-4775 3375);
FORCEADD TAP..1
(675 3700);
FORCEPROP 3 LASTPIN (625 3700) SIG_NAME M_H_CPU1_SA_DQS_DN<2>
J 0
(635 3710);
DISPLAY 0.659574 (635 3710);
PAINT MONO (635 3710);
DISPLAY INVISIBLE (635 3710);
FORCEPROP 1 LASTPIN (625 3700) BN 2
J 0
(613 3708);
DISPLAY 0.680851 (613 3708);
PAINT GREEN (613 3708);
FORCEPROP 2 LAST CDS_LIB standard
J 0
(675 3700);
DISPLAY INVISIBLE (675 3700);
FORCEPROP 1 LAST BODY_TYPE PLUMBING
J 0
(675 3750);
DISPLAY 0.872340 (675 3750);
PAINT GREEN (675 3750);
DISPLAY INVISIBLE (675 3750);
FORCEPROP 1 LAST HDL_TAP TRUE
J 0
(1000 3575);
DISPLAY 0.872340 (1000 3575);
DISPLAY INVISIBLE (1000 3575);
FORCEPROP 1 LAST PATH I150
J 0
(673 3700);
DISPLAY 0.872340 (673 3700);
PAINT GREEN (673 3700);
DISPLAY INVISIBLE (673 3700);
FORCEADD TAP..1
(675 3800);
FORCEPROP 3 LASTPIN (625 3800) SIG_NAME M_H_CPU1_SA_DQS_DN<3>
J 0
(635 3810);
DISPLAY 0.659574 (635 3810);
PAINT MONO (635 3810);
DISPLAY INVISIBLE (635 3810);
FORCEPROP 1 LASTPIN (625 3800) BN 3
J 0
(613 3808);
DISPLAY 0.680851 (613 3808);
PAINT GREEN (613 3808);
FORCEPROP 2 LAST CDS_LIB standard
J 0
(675 3800);
PAINT MONO (675 3800);
DISPLAY INVISIBLE (675 3800);
FORCEPROP 1 LAST BODY_TYPE PLUMBING
J 0
(675 3850);
DISPLAY 0.872340 (675 3850);
PAINT GREEN (675 3850);
DISPLAY INVISIBLE (675 3850);
FORCEPROP 1 LAST HDL_TAP TRUE
J 0
(1000 3675);
DISPLAY 0.872340 (1000 3675);
DISPLAY INVISIBLE (1000 3675);
FORCEPROP 1 LAST PATH I151
J 0
(673 3800);
DISPLAY 0.872340 (673 3800);
PAINT GREEN (673 3800);
DISPLAY INVISIBLE (673 3800);
FORCEADD TAP..1
(500 3950);
FORCEPROP 3 LASTPIN (450 3950) SIG_NAME M_H_CPU1_SA_DQS_DP<4>
J 0
(460 3960);
DISPLAY 0.659574 (460 3960);
PAINT MONO (460 3960);
DISPLAY INVISIBLE (460 3960);
FORCEPROP 1 LASTPIN (450 3950) BN 4
J 0
(438 3958);
DISPLAY 0.680851 (438 3958);
PAINT GREEN (438 3958);
FORCEPROP 2 LAST CDS_LIB standard
J 0
(500 3950);
PAINT MONO (500 3950);
DISPLAY INVISIBLE (500 3950);
FORCEPROP 1 LAST BODY_TYPE PLUMBING
J 0
(500 4000);
DISPLAY 0.872340 (500 4000);
PAINT GREEN (500 4000);
DISPLAY INVISIBLE (500 4000);
FORCEPROP 1 LAST HDL_TAP TRUE
J 0
(825 3825);
DISPLAY 0.872340 (825 3825);
DISPLAY INVISIBLE (825 3825);
FORCEPROP 1 LAST PATH I152
J 0
(498 3950);
DISPLAY 0.872340 (498 3950);
PAINT GREEN (498 3950);
DISPLAY INVISIBLE (498 3950);
FORCEADD TAP..1
(500 4050);
FORCEPROP 3 LASTPIN (450 4050) SIG_NAME M_H_CPU1_SA_DQS_DP<5>
J 0
(460 4060);
DISPLAY 0.659574 (460 4060);
PAINT MONO (460 4060);
DISPLAY INVISIBLE (460 4060);
FORCEPROP 1 LASTPIN (450 4050) BN 5
J 0
(438 4058);
DISPLAY 0.680851 (438 4058);
PAINT GREEN (438 4058);
FORCEPROP 2 LAST CDS_LIB standard
J 0
(500 4050);
DISPLAY INVISIBLE (500 4050);
FORCEPROP 1 LAST BODY_TYPE PLUMBING
J 0
(500 4100);
DISPLAY 0.872340 (500 4100);
PAINT GREEN (500 4100);
DISPLAY INVISIBLE (500 4100);
FORCEPROP 1 LAST HDL_TAP TRUE
J 0
(825 3925);
DISPLAY 0.872340 (825 3925);
DISPLAY INVISIBLE (825 3925);
FORCEPROP 1 LAST PATH I153
J 0
(498 4050);
DISPLAY 0.872340 (498 4050);
PAINT GREEN (498 4050);
DISPLAY INVISIBLE (498 4050);
FORCEADD TAP..1
(500 4350);
FORCEPROP 3 LASTPIN (450 4350) SIG_NAME M_H_CPU1_SA_DQS_DP<8>
J 0
(460 4360);
DISPLAY 0.659574 (460 4360);
PAINT MONO (460 4360);
DISPLAY INVISIBLE (460 4360);
FORCEPROP 1 LASTPIN (450 4350) BN 8
J 0
(438 4358);
DISPLAY 0.680851 (438 4358);
PAINT GREEN (438 4358);
FORCEPROP 2 LAST CDS_LIB standard
J 0
(500 4350);
DISPLAY INVISIBLE (500 4350);
FORCEPROP 1 LAST BODY_TYPE PLUMBING
J 0
(500 4400);
DISPLAY 0.872340 (500 4400);
PAINT GREEN (500 4400);
DISPLAY INVISIBLE (500 4400);
FORCEPROP 1 LAST HDL_TAP TRUE
J 0
(825 4225);
DISPLAY 0.872340 (825 4225);
DISPLAY INVISIBLE (825 4225);
FORCEPROP 1 LAST PATH I154
J 0
(498 4350);
DISPLAY 0.872340 (498 4350);
PAINT GREEN (498 4350);
DISPLAY INVISIBLE (498 4350);
FORCEADD TAP..1
(500 4250);
FORCEPROP 3 LASTPIN (450 4250) SIG_NAME M_H_CPU1_SA_DQS_DP<7>
J 0
(460 4260);
DISPLAY 0.659574 (460 4260);
PAINT MONO (460 4260);
DISPLAY INVISIBLE (460 4260);
FORCEPROP 1 LASTPIN (450 4250) BN 7
J 0
(438 4258);
DISPLAY 0.680851 (438 4258);
PAINT GREEN (438 4258);
FORCEPROP 2 LAST CDS_LIB standard
J 0
(500 4250);
DISPLAY INVISIBLE (500 4250);
FORCEPROP 1 LAST BODY_TYPE PLUMBING
J 0
(500 4300);
DISPLAY 0.872340 (500 4300);
PAINT GREEN (500 4300);
DISPLAY INVISIBLE (500 4300);
FORCEPROP 1 LAST HDL_TAP TRUE
J 0
(825 4125);
DISPLAY 0.872340 (825 4125);
DISPLAY INVISIBLE (825 4125);
FORCEPROP 1 LAST PATH I155
J 0
(498 4250);
DISPLAY 0.872340 (498 4250);
PAINT GREEN (498 4250);
DISPLAY INVISIBLE (498 4250);
FORCEADD TAP..1
(500 4150);
FORCEPROP 3 LASTPIN (450 4150) SIG_NAME M_H_CPU1_SA_DQS_DP<6>
J 0
(460 4160);
DISPLAY 0.659574 (460 4160);
PAINT MONO (460 4160);
DISPLAY INVISIBLE (460 4160);
FORCEPROP 1 LASTPIN (450 4150) BN 6
J 0
(438 4158);
DISPLAY 0.680851 (438 4158);
PAINT GREEN (438 4158);
FORCEPROP 2 LAST CDS_LIB standard
J 0
(500 4150);
DISPLAY INVISIBLE (500 4150);
FORCEPROP 1 LAST BODY_TYPE PLUMBING
J 0
(500 4200);
DISPLAY 0.872340 (500 4200);
PAINT GREEN (500 4200);
DISPLAY INVISIBLE (500 4200);
FORCEPROP 1 LAST HDL_TAP TRUE
J 0
(825 4025);
DISPLAY 0.872340 (825 4025);
DISPLAY INVISIBLE (825 4025);
FORCEPROP 1 LAST PATH I156
J 0
(498 4150);
DISPLAY 0.872340 (498 4150);
PAINT GREEN (498 4150);
DISPLAY INVISIBLE (498 4150);
FORCEADD TAP..1
(675 3900);
FORCEPROP 3 LASTPIN (625 3900) SIG_NAME M_H_CPU1_SA_DQS_DN<4>
J 0
(635 3910);
DISPLAY 0.659574 (635 3910);
PAINT MONO (635 3910);
DISPLAY INVISIBLE (635 3910);
FORCEPROP 1 LASTPIN (625 3900) BN 4
J 0
(613 3908);
DISPLAY 0.680851 (613 3908);
PAINT GREEN (613 3908);
FORCEPROP 2 LAST CDS_LIB standard
J 0
(675 3900);
PAINT MONO (675 3900);
DISPLAY INVISIBLE (675 3900);
FORCEPROP 1 LAST BODY_TYPE PLUMBING
J 0
(675 3950);
DISPLAY 0.872340 (675 3950);
PAINT GREEN (675 3950);
DISPLAY INVISIBLE (675 3950);
FORCEPROP 1 LAST HDL_TAP TRUE
J 0
(1000 3775);
DISPLAY 0.872340 (1000 3775);
DISPLAY INVISIBLE (1000 3775);
FORCEPROP 1 LAST PATH I157
J 0
(673 3900);
DISPLAY 0.872340 (673 3900);
PAINT GREEN (673 3900);
DISPLAY INVISIBLE (673 3900);
FORCEADD TAP..1
(675 4100);
FORCEPROP 3 LASTPIN (625 4100) SIG_NAME M_H_CPU1_SA_DQS_DN<6>
J 0
(635 4110);
DISPLAY 0.659574 (635 4110);
PAINT MONO (635 4110);
DISPLAY INVISIBLE (635 4110);
FORCEPROP 1 LASTPIN (625 4100) BN 6
J 0
(613 4108);
DISPLAY 0.680851 (613 4108);
PAINT GREEN (613 4108);
FORCEPROP 2 LAST CDS_LIB standard
J 0
(675 4100);
DISPLAY INVISIBLE (675 4100);
FORCEPROP 1 LAST BODY_TYPE PLUMBING
J 0
(675 4150);
DISPLAY 0.872340 (675 4150);
PAINT GREEN (675 4150);
DISPLAY INVISIBLE (675 4150);
FORCEPROP 1 LAST HDL_TAP TRUE
J 0
(1000 3975);
DISPLAY 0.872340 (1000 3975);
DISPLAY INVISIBLE (1000 3975);
FORCEPROP 1 LAST PATH I158
J 0
(673 4100);
DISPLAY 0.872340 (673 4100);
PAINT GREEN (673 4100);
DISPLAY INVISIBLE (673 4100);
FORCEADD TAP..1
(675 4000);
FORCEPROP 3 LASTPIN (625 4000) SIG_NAME M_H_CPU1_SA_DQS_DN<5>
J 0
(635 4010);
DISPLAY 0.659574 (635 4010);
PAINT MONO (635 4010);
DISPLAY INVISIBLE (635 4010);
FORCEPROP 1 LASTPIN (625 4000) BN 5
J 0
(613 4008);
DISPLAY 0.680851 (613 4008);
PAINT GREEN (613 4008);
FORCEPROP 2 LAST CDS_LIB standard
J 0
(675 4000);
DISPLAY INVISIBLE (675 4000);
FORCEPROP 1 LAST BODY_TYPE PLUMBING
J 0
(675 4050);
DISPLAY 0.872340 (675 4050);
PAINT GREEN (675 4050);
DISPLAY INVISIBLE (675 4050);
FORCEPROP 1 LAST HDL_TAP TRUE
J 0
(1000 3875);
DISPLAY 0.872340 (1000 3875);
DISPLAY INVISIBLE (1000 3875);
FORCEPROP 1 LAST PATH I159
J 0
(673 4000);
DISPLAY 0.872340 (673 4000);
PAINT GREEN (673 4000);
DISPLAY INVISIBLE (673 4000);
FORCEADD OFFPAGE..1
(-4825 3350);
FORCEPROP 2 LAST $XR0 58 
J 0
(-5046 3350);
DISPLAY 0.638298 (-5046 3350);
PAINT MONO (-5046 3350);
FORCEPROP 2 LAST CDS_LIB standard
J 0
(-4825 3350);
PAINT MONO (-4825 3350);
DISPLAY INVISIBLE (-4825 3350);
FORCEPROP 1 LAST OFFPAGE TRUE
J 0
(-4500 3225);
DISPLAY 0.872340 (-4500 3225);
DISPLAY INVISIBLE (-4500 3225);
FORCEPROP 1 LAST COMMENT_BODY TRUE
J 0
(-4700 3250);
DISPLAY 0.872340 (-4700 3250);
PAINT GREEN (-4700 3250);
DISPLAY INVISIBLE (-4700 3250);
FORCEPROP 2 LAST PATH I16
J 0
(-4775 3425);
DISPLAY 1.021277 (-4775 3425);
DISPLAY INVISIBLE (-4775 3425);
FORCEADD TAP..1
(675 4200);
FORCEPROP 3 LASTPIN (625 4200) SIG_NAME M_H_CPU1_SA_DQS_DN<7>
J 0
(635 4210);
DISPLAY 0.659574 (635 4210);
PAINT MONO (635 4210);
DISPLAY INVISIBLE (635 4210);
FORCEPROP 1 LASTPIN (625 4200) BN 7
J 0
(613 4208);
DISPLAY 0.680851 (613 4208);
PAINT GREEN (613 4208);
FORCEPROP 2 LAST CDS_LIB standard
J 0
(675 4200);
DISPLAY INVISIBLE (675 4200);
FORCEPROP 1 LAST BODY_TYPE PLUMBING
J 0
(675 4250);
DISPLAY 0.872340 (675 4250);
PAINT GREEN (675 4250);
DISPLAY INVISIBLE (675 4250);
FORCEPROP 1 LAST HDL_TAP TRUE
J 0
(1000 4075);
DISPLAY 0.872340 (1000 4075);
DISPLAY INVISIBLE (1000 4075);
FORCEPROP 1 LAST PATH I160
J 0
(673 4200);
DISPLAY 0.872340 (673 4200);
PAINT GREEN (673 4200);
DISPLAY INVISIBLE (673 4200);
FORCEADD TAP..1
(675 4300);
FORCEPROP 3 LASTPIN (625 4300) SIG_NAME M_H_CPU1_SA_DQS_DN<8>
J 0
(635 4310);
DISPLAY 0.659574 (635 4310);
PAINT MONO (635 4310);
DISPLAY INVISIBLE (635 4310);
FORCEPROP 1 LASTPIN (625 4300) BN 8
J 0
(613 4308);
DISPLAY 0.680851 (613 4308);
PAINT GREEN (613 4308);
FORCEPROP 2 LAST CDS_LIB standard
J 0
(675 4300);
DISPLAY INVISIBLE (675 4300);
FORCEPROP 1 LAST BODY_TYPE PLUMBING
J 0
(675 4350);
DISPLAY 0.872340 (675 4350);
PAINT GREEN (675 4350);
DISPLAY INVISIBLE (675 4350);
FORCEPROP 1 LAST HDL_TAP TRUE
J 0
(1000 4175);
DISPLAY 0.872340 (1000 4175);
DISPLAY INVISIBLE (1000 4175);
FORCEPROP 1 LAST PATH I161
J 0
(673 4300);
DISPLAY 0.872340 (673 4300);
PAINT GREEN (673 4300);
DISPLAY INVISIBLE (673 4300);
FORCEADD OFFPAGE..2
(1625 3375);
FORCEPROP 2 LAST $XR1 112 
J 0
(1904 3375);
DISPLAY 0.638298 (1904 3375);
PAINT MONO (1904 3375);
FORCEPROP 2 LAST $XR0 58 
J 0
(1814 3375);
DISPLAY 0.638298 (1814 3375);
PAINT MONO (1814 3375);
FORCEPROP 2 LAST CDS_LIB standard
J 0
(1625 3375);
PAINT MONO (1625 3375);
DISPLAY INVISIBLE (1625 3375);
FORCEPROP 1 LAST OFFPAGE TRUE
J 0
(1950 3250);
DISPLAY 1.170213 (1950 3250);
PAINT GREEN (1950 3250);
DISPLAY INVISIBLE (1950 3250);
FORCEPROP 1 LAST COMMENT_BODY TRUE
J 0
(1580 3280);
DISPLAY 1.170213 (1580 3280);
PAINT GREEN (1580 3280);
DISPLAY INVISIBLE (1580 3280);
FORCEPROP 2 LAST PATH I162
J 0
(1800 3450);
DISPLAY 1.021277 (1800 3450);
DISPLAY INVISIBLE (1800 3450);
FORCEADD OFFPAGE..2
(1625 3425);
FORCEPROP 2 LAST $XR1 112 
J 0
(1904 3425);
DISPLAY 0.638298 (1904 3425);
PAINT MONO (1904 3425);
FORCEPROP 2 LAST $XR0 58 
J 0
(1814 3425);
DISPLAY 0.638298 (1814 3425);
PAINT MONO (1814 3425);
FORCEPROP 2 LAST CDS_LIB standard
J 0
(1625 3425);
PAINT MONO (1625 3425);
DISPLAY INVISIBLE (1625 3425);
FORCEPROP 1 LAST OFFPAGE TRUE
J 0
(1950 3300);
DISPLAY 1.170213 (1950 3300);
PAINT GREEN (1950 3300);
DISPLAY INVISIBLE (1950 3300);
FORCEPROP 1 LAST COMMENT_BODY TRUE
J 0
(1580 3330);
DISPLAY 1.170213 (1580 3330);
PAINT GREEN (1580 3330);
DISPLAY INVISIBLE (1580 3330);
FORCEPROP 2 LAST PATH I163
J 0
(1800 3500);
DISPLAY 1.021277 (1800 3500);
DISPLAY INVISIBLE (1800 3500);
FORCEADD OFFPAGE..3
(-1425 4475);
FORCEPROP 2 LAST $XR1 112 
J 0
(-1121 4475);
DISPLAY 0.638298 (-1121 4475);
PAINT MONO (-1121 4475);
FORCEPROP 2 LAST $XR0 58 
J 0
(-1211 4475);
DISPLAY 0.638298 (-1211 4475);
PAINT MONO (-1211 4475);
FORCEPROP 2 LAST CDS_LIB standard
J 2
(-1425 4475);
DISPLAY INVISIBLE (-1425 4475);
FORCEPROP 1 LAST OFFPAGE TRUE
J 0
(-1100 4350);
DISPLAY 0.872340 (-1100 4350);
DISPLAY INVISIBLE (-1100 4350);
FORCEPROP 1 LAST COMMENT_BODY TRUE
J 0
(-1475 4375);
DISPLAY 0.872340 (-1475 4375);
PAINT GREEN (-1475 4375);
DISPLAY INVISIBLE (-1475 4375);
FORCEPROP 2 LAST PATH I164
J 0
(-1225 4550);
DISPLAY 1.021277 (-1225 4550);
DISPLAY INVISIBLE (-1225 4550);
FORCEADD TAP..1
(500 4450);
FORCEPROP 3 LASTPIN (450 4450) SIG_NAME M_H_CPU1_SA_DQS_DP<9>
J 0
(460 4460);
DISPLAY 0.659574 (460 4460);
PAINT MONO (460 4460);
DISPLAY INVISIBLE (460 4460);
FORCEPROP 1 LASTPIN (450 4450) BN 9
J 0
(438 4458);
DISPLAY 0.680851 (438 4458);
PAINT GREEN (438 4458);
FORCEPROP 2 LAST CDS_LIB standard
J 0
(500 4450);
DISPLAY INVISIBLE (500 4450);
FORCEPROP 1 LAST BODY_TYPE PLUMBING
J 0
(500 4500);
DISPLAY 0.872340 (500 4500);
PAINT GREEN (500 4500);
DISPLAY INVISIBLE (500 4500);
FORCEPROP 1 LAST HDL_TAP TRUE
J 0
(825 4325);
DISPLAY 0.872340 (825 4325);
DISPLAY INVISIBLE (825 4325);
FORCEPROP 1 LAST PATH I165
J 0
(498 4450);
DISPLAY 0.872340 (498 4450);
PAINT GREEN (498 4450);
DISPLAY INVISIBLE (498 4450);
FORCEADD TAP..1
(675 4400);
FORCEPROP 3 LASTPIN (625 4400) SIG_NAME M_H_CPU1_SA_DQS_DN<9>
J 0
(635 4410);
DISPLAY 0.659574 (635 4410);
PAINT MONO (635 4410);
DISPLAY INVISIBLE (635 4410);
FORCEPROP 1 LASTPIN (625 4400) BN 9
J 0
(613 4408);
DISPLAY 0.680851 (613 4408);
PAINT GREEN (613 4408);
FORCEPROP 2 LAST CDS_LIB standard
J 0
(675 4400);
DISPLAY INVISIBLE (675 4400);
FORCEPROP 1 LAST BODY_TYPE PLUMBING
J 0
(675 4450);
DISPLAY 0.872340 (675 4450);
PAINT GREEN (675 4450);
DISPLAY INVISIBLE (675 4450);
FORCEPROP 1 LAST HDL_TAP TRUE
J 0
(1000 4275);
DISPLAY 0.872340 (1000 4275);
DISPLAY INVISIBLE (1000 4275);
FORCEPROP 1 LAST PATH I166
J 0
(673 4400);
DISPLAY 0.872340 (673 4400);
PAINT GREEN (673 4400);
DISPLAY INVISIBLE (673 4400);
FORCEADD OFFPAGE..2
(1625 4475);
FORCEPROP 2 LAST $XR1 112 
J 0
(1904 4475);
DISPLAY 0.638298 (1904 4475);
PAINT MONO (1904 4475);
FORCEPROP 2 LAST $XR0 58 
J 0
(1814 4475);
DISPLAY 0.638298 (1814 4475);
PAINT MONO (1814 4475);
FORCEPROP 2 LAST CDS_LIB standard
J 0
(1625 4475);
PAINT MONO (1625 4475);
DISPLAY INVISIBLE (1625 4475);
FORCEPROP 1 LAST OFFPAGE TRUE
J 0
(1950 4350);
DISPLAY 1.170213 (1950 4350);
PAINT GREEN (1950 4350);
DISPLAY INVISIBLE (1950 4350);
FORCEPROP 1 LAST COMMENT_BODY TRUE
J 0
(1580 4380);
DISPLAY 1.170213 (1580 4380);
PAINT GREEN (1580 4380);
DISPLAY INVISIBLE (1580 4380);
FORCEPROP 2 LAST PATH I167
J 0
(1800 4550);
DISPLAY 1.021277 (1800 4550);
DISPLAY INVISIBLE (1800 4550);
FORCEADD OFFPAGE..2
(1625 4425);
FORCEPROP 2 LAST $XR1 112 
J 0
(1904 4425);
DISPLAY 0.638298 (1904 4425);
PAINT MONO (1904 4425);
FORCEPROP 2 LAST $XR0 58 
J 0
(1814 4425);
DISPLAY 0.638298 (1814 4425);
PAINT MONO (1814 4425);
FORCEPROP 2 LAST CDS_LIB standard
J 0
(1625 4425);
PAINT MONO (1625 4425);
DISPLAY INVISIBLE (1625 4425);
FORCEPROP 1 LAST OFFPAGE TRUE
J 0
(1950 4300);
DISPLAY 1.170213 (1950 4300);
PAINT GREEN (1950 4300);
DISPLAY INVISIBLE (1950 4300);
FORCEPROP 1 LAST COMMENT_BODY TRUE
J 0
(1580 4330);
DISPLAY 1.170213 (1580 4330);
PAINT GREEN (1580 4330);
DISPLAY INVISIBLE (1580 4330);
FORCEPROP 2 LAST PATH I168
J 0
(1800 4500);
DISPLAY 1.021277 (1800 4500);
DISPLAY INVISIBLE (1800 4500);
FORCEADD VCC_CORE..1
(2175 5000);
FORCEPROP 3 LASTPIN (2175 4950) SIG_NAME P12V_S3_AUX_CPU1_NVDIMM\g
J 0
(2185 4960);
DISPLAY 0.659574 (2185 4960);
PAINT MONO (2185 4960);
DISPLAY INVISIBLE (2185 4960);
FORCEPROP 1 LAST HDL_POWER P12V_S3_AUX_CPU1_NVDIMM
J 1
(2175 5050);
DISPLAY 1.148936 (2175 5050);
PAINT GREEN (2175 5050);
FORCEPROP 2 LAST CDS_LIB logical_power
J 0
(2175 5000);
PAINT MONO (2175 5000);
DISPLAY INVISIBLE (2175 5000);
FORCEPROP 1 LAST PATH I169
J 0
(2225 5025);
DISPLAY 0.872340 (2225 5025);
PAINT AQUA (2225 5025);
DISPLAY INVISIBLE (2225 5025);
FORCEADD OFFPAGE..1
(-4825 3500);
FORCEPROP 2 LAST $XR0 58 
J 0
(-5046 3500);
DISPLAY 0.638298 (-5046 3500);
PAINT MONO (-5046 3500);
FORCEPROP 2 LAST CDS_LIB standard
J 0
(-4825 3500);
PAINT MONO (-4825 3500);
DISPLAY INVISIBLE (-4825 3500);
FORCEPROP 1 LAST OFFPAGE TRUE
J 0
(-4500 3375);
DISPLAY 0.872340 (-4500 3375);
DISPLAY INVISIBLE (-4500 3375);
FORCEPROP 1 LAST COMMENT_BODY TRUE
J 0
(-4700 3400);
DISPLAY 0.872340 (-4700 3400);
PAINT GREEN (-4700 3400);
DISPLAY INVISIBLE (-4700 3400);
FORCEPROP 2 LAST PATH I17
J 0
(-4775 3575);
DISPLAY 1.021277 (-4775 3575);
DISPLAY INVISIBLE (-4775 3575);
FORCEADD UNIVERSAL_GND..1
(3875 750);
FORCEPROP 3 LASTPIN (3875 800) SIG_NAME GND\g
J 0
(3885 810);
DISPLAY 0.659574 (3885 810);
PAINT MONO (3885 810);
DISPLAY INVISIBLE (3885 810);
FORCEPROP 1 LAST PATH I171
J 0
(3950 750);
DISPLAY 0.872340 (3950 750);
PAINT AQUA (3950 750);
DISPLAY INVISIBLE (3950 750);
FORCEPROP 1 LAST HDL_POWER GND
J 1
(3900 675);
DISPLAY 0.872340 (3900 675);
PAINT GREEN (3900 675);
DISPLAY INVISIBLE (3900 675);
FORCEPROP 2 LAST CDS_LIB logical_power
J 0
(3875 750);
PAINT MONO (3875 750);
DISPLAY INVISIBLE (3875 750);
FORCEADD OFFPAGE..3
R 2
(-4825 3075);
FORCEPROP 2 LAST $XR1 112 
J 0
(-5194 3075);
DISPLAY 0.638298 (-5194 3075);
PAINT MONO (-5194 3075);
FORCEPROP 2 LAST $XR0 58 
J 0
(-5074 3075);
DISPLAY 0.638298 (-5074 3075);
PAINT MONO (-5074 3075);
FORCEPROP 2 LAST CDS_LIB standard
J 0
(-4825 3075);
PAINT MONO (-4825 3075);
DISPLAY INVISIBLE (-4825 3075);
FORCEPROP 1 LAST OFFPAGE TRUE
J 2
(-5150 2950);
DISPLAY 0.872340 (-5150 2950);
DISPLAY INVISIBLE (-5150 2950);
FORCEPROP 1 LAST COMMENT_BODY TRUE
J 2
(-4775 2975);
DISPLAY 0.872340 (-4775 2975);
PAINT GREEN (-4775 2975);
DISPLAY INVISIBLE (-4775 2975);
FORCEPROP 2 LAST PATH I172
J 0
(-4775 3150);
DISPLAY 1.021277 (-4775 3150);
DISPLAY INVISIBLE (-4775 3150);
FORCEADD OFFPAGE..1
(-4825 3150);
FORCEPROP 2 LAST $XR0 58 
J 0
(-5046 3150);
DISPLAY 0.638298 (-5046 3150);
PAINT MONO (-5046 3150);
FORCEPROP 2 LAST CDS_LIB standard
J 0
(-4825 3150);
PAINT MONO (-4825 3150);
DISPLAY INVISIBLE (-4825 3150);
FORCEPROP 1 LAST OFFPAGE TRUE
J 0
(-4500 3025);
DISPLAY 0.872340 (-4500 3025);
DISPLAY INVISIBLE (-4500 3025);
FORCEPROP 1 LAST COMMENT_BODY TRUE
J 0
(-4700 3050);
DISPLAY 0.872340 (-4700 3050);
PAINT GREEN (-4700 3050);
DISPLAY INVISIBLE (-4700 3050);
FORCEPROP 2 LAST PATH I173
J 0
(-4775 3225);
DISPLAY 1.021277 (-4775 3225);
DISPLAY INVISIBLE (-4775 3225);
FORCEADD OFFPAGE..1
(-4825 3200);
FORCEPROP 2 LAST $XR0 58 
J 0
(-5046 3200);
DISPLAY 0.638298 (-5046 3200);
PAINT MONO (-5046 3200);
FORCEPROP 2 LAST CDS_LIB standard
J 0
(-4825 3200);
PAINT MONO (-4825 3200);
DISPLAY INVISIBLE (-4825 3200);
FORCEPROP 1 LAST OFFPAGE TRUE
J 0
(-4500 3075);
DISPLAY 0.872340 (-4500 3075);
DISPLAY INVISIBLE (-4500 3075);
FORCEPROP 1 LAST COMMENT_BODY TRUE
J 0
(-4700 3100);
DISPLAY 0.872340 (-4700 3100);
PAINT GREEN (-4700 3100);
DISPLAY INVISIBLE (-4700 3100);
FORCEPROP 2 LAST PATH I174
J 0
(-4775 3275);
DISPLAY 1.021277 (-4775 3275);
DISPLAY INVISIBLE (-4775 3275);
FORCEADD TAP..1
R 2
(-3900 2500);
FORCEPROP 3 LASTPIN (-3850 2500) SIG_NAME M_H_CPU1_SB_CB<5>
J 0
(-3840 2510);
DISPLAY 0.659574 (-3840 2510);
PAINT MONO (-3840 2510);
DISPLAY INVISIBLE (-3840 2510);
FORCEPROP 1 LASTPIN (-3850 2500) BN 5
J 2
(-3838 2508);
DISPLAY 0.680851 (-3838 2508);
PAINT GREEN (-3838 2508);
FORCEPROP 2 LAST CDS_LIB standard
J 0
(-3900 2500);
DISPLAY INVISIBLE (-3900 2500);
FORCEPROP 1 LAST BODY_TYPE PLUMBING
J 2
(-3900 2550);
DISPLAY 0.872340 (-3900 2550);
PAINT GREEN (-3900 2550);
DISPLAY INVISIBLE (-3900 2550);
FORCEPROP 1 LAST HDL_TAP TRUE
J 2
(-4225 2375);
DISPLAY 0.872340 (-4225 2375);
DISPLAY INVISIBLE (-4225 2375);
FORCEPROP 1 LAST PATH I175
J 2
(-3898 2500);
DISPLAY 0.872340 (-3898 2500);
PAINT GREEN (-3898 2500);
DISPLAY INVISIBLE (-3898 2500);
FORCEADD TAP..1
R 2
(-3900 2450);
FORCEPROP 3 LASTPIN (-3850 2450) SIG_NAME M_H_CPU1_SB_CB<4>
J 0
(-3840 2460);
DISPLAY 0.659574 (-3840 2460);
PAINT MONO (-3840 2460);
DISPLAY INVISIBLE (-3840 2460);
FORCEPROP 1 LASTPIN (-3850 2450) BN 4
J 2
(-3838 2458);
DISPLAY 0.680851 (-3838 2458);
PAINT GREEN (-3838 2458);
FORCEPROP 2 LAST CDS_LIB standard
J 0
(-3900 2450);
DISPLAY INVISIBLE (-3900 2450);
FORCEPROP 1 LAST BODY_TYPE PLUMBING
J 2
(-3900 2500);
DISPLAY 0.872340 (-3900 2500);
PAINT GREEN (-3900 2500);
DISPLAY INVISIBLE (-3900 2500);
FORCEPROP 1 LAST HDL_TAP TRUE
J 2
(-4225 2325);
DISPLAY 0.872340 (-4225 2325);
DISPLAY INVISIBLE (-4225 2325);
FORCEPROP 1 LAST PATH I176
J 2
(-3898 2450);
DISPLAY 0.872340 (-3898 2450);
PAINT GREEN (-3898 2450);
DISPLAY INVISIBLE (-3898 2450);
FORCEADD SCONN288_ADR50017P087CC..3
(3025 2825);
FORCEPROP 1 LAST PART_NUMBER DFHST8FS460
J 0
(2570 4749);
DISPLAY 0.723404 (2570 4749);
PAINT GREEN (2570 4749);
DISPLAY INVISIBLE (2570 4749);
FORCEPROP 1 LAST MATERIAL IO
J 0
(2570 4622);
DISPLAY 0.723404 (2570 4622);
PAINT GREEN (2570 4622);
FORCEPROP 2 LAST PART_TYPE SMLF
J 0
(2575 4900);
DISPLAY 1.021277 (2575 4900);
FORCEPROP 2 LAST VALUE SCONN288_ADR50017-P087CC
J 0
(2575 4850);
DISPLAY 1.021277 (2575 4850);
FORCEPROP 1 LAST $LOCATION J32
J 0
(2575 4800);
DISPLAY 0.723404 (2575 4800);
PAINT GREEN (2575 4800);
FORCEPROP 0 LASTPIN (3625 1200) $PN G1
J 0
(3635 1210);
DISPLAY 0.680851 (3635 1210);
PAINT MONO (3635 1210);
FORCEPROP 0 LASTPIN (3625 1150) $PN G2
J 0
(3635 1160);
DISPLAY 0.680851 (3635 1160);
PAINT MONO (3635 1160);
FORCEPROP 0 LASTPIN (3625 1100) $PN G3
J 0
(3635 1110);
DISPLAY 0.680851 (3635 1110);
PAINT MONO (3635 1110);
FORCEPROP 0 LASTPIN (2425 4350) $PN 1
J 2
(2415 4360);
DISPLAY 0.680851 (2415 4360);
PAINT MONO (2415 4360);
FORCEPROP 0 LASTPIN (2425 4400) $PN 145
J 2
(2415 4410);
DISPLAY 0.680851 (2415 4410);
PAINT MONO (2415 4410);
FORCEPROP 0 LASTPIN (2425 4450) $PN 146
J 2
(2415 4460);
DISPLAY 0.680851 (2415 4460);
PAINT MONO (2415 4460);
FORCEPROP 0 LASTPIN (3625 1300) $PN 6
J 0
(3635 1310);
DISPLAY 0.680851 (3635 1310);
PAINT MONO (3635 1310);
FORCEPROP 0 LASTPIN (3625 1350) $PN 8
J 0
(3635 1360);
DISPLAY 0.680851 (3635 1360);
PAINT MONO (3635 1360);
FORCEPROP 0 LASTPIN (3625 1400) $PN 10
J 0
(3635 1410);
DISPLAY 0.680851 (3635 1410);
PAINT MONO (3635 1410);
FORCEPROP 0 LASTPIN (3625 1450) $PN 13
J 0
(3635 1460);
DISPLAY 0.680851 (3635 1460);
PAINT MONO (3635 1460);
FORCEPROP 0 LASTPIN (3625 1500) $PN 15
J 0
(3635 1510);
DISPLAY 0.680851 (3635 1510);
PAINT MONO (3635 1510);
FORCEPROP 0 LASTPIN (3625 1550) $PN 17
J 0
(3635 1560);
DISPLAY 0.680851 (3635 1560);
PAINT MONO (3635 1560);
FORCEPROP 0 LASTPIN (3625 1600) $PN 19
J 0
(3635 1610);
DISPLAY 0.680851 (3635 1610);
PAINT MONO (3635 1610);
FORCEPROP 0 LASTPIN (3625 1650) $PN 21
J 0
(3635 1660);
DISPLAY 0.680851 (3635 1660);
PAINT MONO (3635 1660);
FORCEPROP 0 LASTPIN (3625 1700) $PN 24
J 0
(3635 1710);
DISPLAY 0.680851 (3635 1710);
PAINT MONO (3635 1710);
FORCEPROP 0 LASTPIN (3625 1750) $PN 26
J 0
(3635 1760);
DISPLAY 0.680851 (3635 1760);
PAINT MONO (3635 1760);
FORCEPROP 0 LASTPIN (3625 1800) $PN 28
J 0
(3635 1810);
DISPLAY 0.680851 (3635 1810);
PAINT MONO (3635 1810);
FORCEPROP 0 LASTPIN (3625 1850) $PN 30
J 0
(3635 1860);
DISPLAY 0.680851 (3635 1860);
PAINT MONO (3635 1860);
FORCEPROP 0 LASTPIN (3625 1900) $PN 32
J 0
(3635 1910);
DISPLAY 0.680851 (3635 1910);
PAINT MONO (3635 1910);
FORCEPROP 0 LASTPIN (3625 1950) $PN 35
J 0
(3635 1960);
DISPLAY 0.680851 (3635 1960);
PAINT MONO (3635 1960);
FORCEPROP 0 LASTPIN (3625 2000) $PN 37
J 0
(3635 2010);
DISPLAY 0.680851 (3635 2010);
PAINT MONO (3635 2010);
FORCEPROP 0 LASTPIN (3625 2050) $PN 39
J 0
(3635 2060);
DISPLAY 0.680851 (3635 2060);
PAINT MONO (3635 2060);
FORCEPROP 0 LASTPIN (3625 2100) $PN 41
J 0
(3635 2110);
DISPLAY 0.680851 (3635 2110);
PAINT MONO (3635 2110);
FORCEPROP 0 LASTPIN (3625 2150) $PN 43
J 0
(3635 2160);
DISPLAY 0.680851 (3635 2160);
PAINT MONO (3635 2160);
FORCEPROP 0 LASTPIN (3625 2200) $PN 46
J 0
(3635 2210);
DISPLAY 0.680851 (3635 2210);
PAINT MONO (3635 2210);
FORCEPROP 0 LASTPIN (3625 2250) $PN 48
J 0
(3635 2260);
DISPLAY 0.680851 (3635 2260);
PAINT MONO (3635 2260);
FORCEPROP 0 LASTPIN (3625 2300) $PN 50
J 0
(3635 2310);
DISPLAY 0.680851 (3635 2310);
PAINT MONO (3635 2310);
FORCEPROP 0 LASTPIN (3625 2350) $PN 52
J 0
(3635 2360);
DISPLAY 0.680851 (3635 2360);
PAINT MONO (3635 2360);
FORCEPROP 0 LASTPIN (3625 2400) $PN 54
J 0
(3635 2410);
DISPLAY 0.680851 (3635 2410);
PAINT MONO (3635 2410);
FORCEPROP 0 LASTPIN (3625 2450) $PN 57
J 0
(3635 2460);
DISPLAY 0.680851 (3635 2460);
PAINT MONO (3635 2460);
FORCEPROP 0 LASTPIN (3625 2500) $PN 59
J 0
(3635 2510);
DISPLAY 0.680851 (3635 2510);
PAINT MONO (3635 2510);
FORCEPROP 0 LASTPIN (3625 2550) $PN 61
J 0
(3635 2560);
DISPLAY 0.680851 (3635 2560);
PAINT MONO (3635 2560);
FORCEPROP 0 LASTPIN (3625 2600) $PN 63
J 0
(3635 2610);
DISPLAY 0.680851 (3635 2610);
PAINT MONO (3635 2610);
FORCEPROP 0 LASTPIN (3625 2650) $PN 65
J 0
(3635 2660);
DISPLAY 0.680851 (3635 2660);
PAINT MONO (3635 2660);
FORCEPROP 0 LASTPIN (3625 2700) $PN 67
J 0
(3635 2710);
DISPLAY 0.680851 (3635 2710);
PAINT MONO (3635 2710);
FORCEPROP 0 LASTPIN (3625 2750) $PN 69
J 0
(3635 2760);
DISPLAY 0.680851 (3635 2760);
PAINT MONO (3635 2760);
FORCEPROP 0 LASTPIN (3625 2800) $PN 71
J 0
(3635 2810);
DISPLAY 0.680851 (3635 2810);
PAINT MONO (3635 2810);
FORCEPROP 0 LASTPIN (3625 2850) $PN 73
J 0
(3635 2860);
DISPLAY 0.680851 (3635 2860);
PAINT MONO (3635 2860);
FORCEPROP 0 LASTPIN (3625 2900) $PN 75
J 0
(3635 2910);
DISPLAY 0.680851 (3635 2910);
PAINT MONO (3635 2910);
FORCEPROP 0 LASTPIN (3625 2950) $PN 77
J 0
(3635 2960);
DISPLAY 0.680851 (3635 2960);
PAINT MONO (3635 2960);
FORCEPROP 0 LASTPIN (3625 3000) $PN 79
J 0
(3635 3010);
DISPLAY 0.680851 (3635 3010);
PAINT MONO (3635 3010);
FORCEPROP 0 LASTPIN (3625 3050) $PN 81
J 0
(3635 3060);
DISPLAY 0.680851 (3635 3060);
PAINT MONO (3635 3060);
FORCEPROP 0 LASTPIN (3625 3100) $PN 83
J 0
(3635 3110);
DISPLAY 0.680851 (3635 3110);
PAINT MONO (3635 3110);
FORCEPROP 0 LASTPIN (3625 3150) $PN 85
J 0
(3635 3160);
DISPLAY 0.680851 (3635 3160);
PAINT MONO (3635 3160);
FORCEPROP 0 LASTPIN (3625 3200) $PN 88
J 0
(3635 3210);
DISPLAY 0.680851 (3635 3210);
PAINT MONO (3635 3210);
FORCEPROP 0 LASTPIN (3625 3250) $PN 90
J 0
(3635 3260);
DISPLAY 0.680851 (3635 3260);
PAINT MONO (3635 3260);
FORCEPROP 0 LASTPIN (3625 3300) $PN 92
J 0
(3635 3310);
DISPLAY 0.680851 (3635 3310);
PAINT MONO (3635 3310);
FORCEPROP 0 LASTPIN (3625 3350) $PN 95
J 0
(3635 3360);
DISPLAY 0.680851 (3635 3360);
PAINT MONO (3635 3360);
FORCEPROP 0 LASTPIN (3625 3400) $PN 97
J 0
(3635 3410);
DISPLAY 0.680851 (3635 3410);
PAINT MONO (3635 3410);
FORCEPROP 0 LASTPIN (3625 3450) $PN 99
J 0
(3635 3460);
DISPLAY 0.680851 (3635 3460);
PAINT MONO (3635 3460);
FORCEPROP 0 LASTPIN (3625 3500) $PN 101
J 0
(3635 3510);
DISPLAY 0.680851 (3635 3510);
PAINT MONO (3635 3510);
FORCEPROP 0 LASTPIN (3625 3550) $PN 103
J 0
(3635 3560);
DISPLAY 0.680851 (3635 3560);
PAINT MONO (3635 3560);
FORCEPROP 0 LASTPIN (3625 3600) $PN 106
J 0
(3635 3610);
DISPLAY 0.680851 (3635 3610);
PAINT MONO (3635 3610);
FORCEPROP 0 LASTPIN (3625 3650) $PN 108
J 0
(3635 3660);
DISPLAY 0.680851 (3635 3660);
PAINT MONO (3635 3660);
FORCEPROP 0 LASTPIN (3625 3700) $PN 110
J 0
(3635 3710);
DISPLAY 0.680851 (3635 3710);
PAINT MONO (3635 3710);
FORCEPROP 0 LASTPIN (3625 3750) $PN 112
J 0
(3635 3760);
DISPLAY 0.680851 (3635 3760);
PAINT MONO (3635 3760);
FORCEPROP 0 LASTPIN (3625 3800) $PN 114
J 0
(3635 3810);
DISPLAY 0.680851 (3635 3810);
PAINT MONO (3635 3810);
FORCEPROP 0 LASTPIN (3625 3850) $PN 117
J 0
(3635 3860);
DISPLAY 0.680851 (3635 3860);
PAINT MONO (3635 3860);
FORCEPROP 0 LASTPIN (3625 3900) $PN 119
J 0
(3635 3910);
DISPLAY 0.680851 (3635 3910);
PAINT MONO (3635 3910);
FORCEPROP 0 LASTPIN (3625 3950) $PN 121
J 0
(3635 3960);
DISPLAY 0.680851 (3635 3960);
PAINT MONO (3635 3960);
FORCEPROP 0 LASTPIN (3625 4000) $PN 123
J 0
(3635 4010);
DISPLAY 0.680851 (3635 4010);
PAINT MONO (3635 4010);
FORCEPROP 0 LASTPIN (3625 4050) $PN 125
J 0
(3635 4060);
DISPLAY 0.680851 (3635 4060);
PAINT MONO (3635 4060);
FORCEPROP 0 LASTPIN (3625 4100) $PN 128
J 0
(3635 4110);
DISPLAY 0.680851 (3635 4110);
PAINT MONO (3635 4110);
FORCEPROP 0 LASTPIN (3625 4150) $PN 130
J 0
(3635 4160);
DISPLAY 0.680851 (3635 4160);
PAINT MONO (3635 4160);
FORCEPROP 0 LASTPIN (3625 4200) $PN 132
J 0
(3635 4210);
DISPLAY 0.680851 (3635 4210);
PAINT MONO (3635 4210);
FORCEPROP 0 LASTPIN (3625 4250) $PN 134
J 0
(3635 4260);
DISPLAY 0.680851 (3635 4260);
PAINT MONO (3635 4260);
FORCEPROP 0 LASTPIN (3625 4300) $PN 136
J 0
(3635 4310);
DISPLAY 0.680851 (3635 4310);
PAINT MONO (3635 4310);
FORCEPROP 0 LASTPIN (3625 4350) $PN 139
J 0
(3635 4360);
DISPLAY 0.680851 (3635 4360);
PAINT MONO (3635 4360);
FORCEPROP 0 LASTPIN (3625 4400) $PN 141
J 0
(3635 4410);
DISPLAY 0.680851 (3635 4410);
PAINT MONO (3635 4410);
FORCEPROP 0 LASTPIN (3625 4450) $PN 143
J 0
(3635 4460);
DISPLAY 0.680851 (3635 4460);
PAINT MONO (3635 4460);
FORCEPROP 0 LASTPIN (2425 1200) $PN 151
J 2
(2415 1210);
DISPLAY 0.680851 (2415 1210);
PAINT MONO (2415 1210);
FORCEPROP 0 LASTPIN (2425 1250) $PN 153
J 2
(2415 1260);
DISPLAY 0.680851 (2415 1260);
PAINT MONO (2415 1260);
FORCEPROP 0 LASTPIN (2425 1300) $PN 155
J 2
(2415 1310);
DISPLAY 0.680851 (2415 1310);
PAINT MONO (2415 1310);
FORCEPROP 0 LASTPIN (2425 1350) $PN 158
J 2
(2415 1360);
DISPLAY 0.680851 (2415 1360);
PAINT MONO (2415 1360);
FORCEPROP 0 LASTPIN (2425 1400) $PN 160
J 2
(2415 1410);
DISPLAY 0.680851 (2415 1410);
PAINT MONO (2415 1410);
FORCEPROP 0 LASTPIN (2425 1450) $PN 162
J 2
(2415 1460);
DISPLAY 0.680851 (2415 1460);
PAINT MONO (2415 1460);
FORCEPROP 0 LASTPIN (2425 1500) $PN 164
J 2
(2415 1510);
DISPLAY 0.680851 (2415 1510);
PAINT MONO (2415 1510);
FORCEPROP 0 LASTPIN (2425 1550) $PN 166
J 2
(2415 1560);
DISPLAY 0.680851 (2415 1560);
PAINT MONO (2415 1560);
FORCEPROP 0 LASTPIN (2425 1600) $PN 169
J 2
(2415 1610);
DISPLAY 0.680851 (2415 1610);
PAINT MONO (2415 1610);
FORCEPROP 0 LASTPIN (2425 1650) $PN 171
J 2
(2415 1660);
DISPLAY 0.680851 (2415 1660);
PAINT MONO (2415 1660);
FORCEPROP 0 LASTPIN (2425 1700) $PN 173
J 2
(2415 1710);
DISPLAY 0.680851 (2415 1710);
PAINT MONO (2415 1710);
FORCEPROP 0 LASTPIN (2425 1750) $PN 175
J 2
(2415 1760);
DISPLAY 0.680851 (2415 1760);
PAINT MONO (2415 1760);
FORCEPROP 0 LASTPIN (2425 1800) $PN 177
J 2
(2415 1810);
DISPLAY 0.680851 (2415 1810);
PAINT MONO (2415 1810);
FORCEPROP 0 LASTPIN (2425 1850) $PN 180
J 2
(2415 1860);
DISPLAY 0.680851 (2415 1860);
PAINT MONO (2415 1860);
FORCEPROP 0 LASTPIN (2425 1900) $PN 182
J 2
(2415 1910);
DISPLAY 0.680851 (2415 1910);
PAINT MONO (2415 1910);
FORCEPROP 0 LASTPIN (2425 1950) $PN 184
J 2
(2415 1960);
DISPLAY 0.680851 (2415 1960);
PAINT MONO (2415 1960);
FORCEPROP 0 LASTPIN (2425 2000) $PN 186
J 2
(2415 2010);
DISPLAY 0.680851 (2415 2010);
PAINT MONO (2415 2010);
FORCEPROP 0 LASTPIN (2425 2050) $PN 188
J 2
(2415 2060);
DISPLAY 0.680851 (2415 2060);
PAINT MONO (2415 2060);
FORCEPROP 0 LASTPIN (2425 2100) $PN 191
J 2
(2415 2110);
DISPLAY 0.680851 (2415 2110);
PAINT MONO (2415 2110);
FORCEPROP 0 LASTPIN (2425 2150) $PN 193
J 2
(2415 2160);
DISPLAY 0.680851 (2415 2160);
PAINT MONO (2415 2160);
FORCEPROP 0 LASTPIN (2425 2200) $PN 195
J 2
(2415 2210);
DISPLAY 0.680851 (2415 2210);
PAINT MONO (2415 2210);
FORCEPROP 0 LASTPIN (2425 2250) $PN 197
J 2
(2415 2260);
DISPLAY 0.680851 (2415 2260);
PAINT MONO (2415 2260);
FORCEPROP 0 LASTPIN (2425 2300) $PN 199
J 2
(2415 2310);
DISPLAY 0.680851 (2415 2310);
PAINT MONO (2415 2310);
FORCEPROP 0 LASTPIN (2425 2350) $PN 202
J 2
(2415 2360);
DISPLAY 0.680851 (2415 2360);
PAINT MONO (2415 2360);
FORCEPROP 0 LASTPIN (2425 2400) $PN 204
J 2
(2415 2410);
DISPLAY 0.680851 (2415 2410);
PAINT MONO (2415 2410);
FORCEPROP 0 LASTPIN (2425 2450) $PN 206
J 2
(2415 2460);
DISPLAY 0.680851 (2415 2460);
PAINT MONO (2415 2460);
FORCEPROP 0 LASTPIN (2425 2500) $PN 208
J 2
(2415 2510);
DISPLAY 0.680851 (2415 2510);
PAINT MONO (2415 2510);
FORCEPROP 0 LASTPIN (2425 2550) $PN 210
J 2
(2415 2560);
DISPLAY 0.680851 (2415 2560);
PAINT MONO (2415 2560);
FORCEPROP 0 LASTPIN (2425 2600) $PN 212
J 2
(2415 2610);
DISPLAY 0.680851 (2415 2610);
PAINT MONO (2415 2610);
FORCEPROP 0 LASTPIN (2425 2650) $PN 214
J 2
(2415 2660);
DISPLAY 0.680851 (2415 2660);
PAINT MONO (2415 2660);
FORCEPROP 0 LASTPIN (2425 2700) $PN 216
J 2
(2415 2710);
DISPLAY 0.680851 (2415 2710);
PAINT MONO (2415 2710);
FORCEPROP 0 LASTPIN (2425 2750) $PN 219
J 2
(2415 2760);
DISPLAY 0.680851 (2415 2760);
PAINT MONO (2415 2760);
FORCEPROP 0 LASTPIN (2425 2800) $PN 222
J 2
(2415 2810);
DISPLAY 0.680851 (2415 2810);
PAINT MONO (2415 2810);
FORCEPROP 0 LASTPIN (2425 2850) $PN 224
J 2
(2415 2860);
DISPLAY 0.680851 (2415 2860);
PAINT MONO (2415 2860);
FORCEPROP 0 LASTPIN (2425 2900) $PN 226
J 2
(2415 2910);
DISPLAY 0.680851 (2415 2910);
PAINT MONO (2415 2910);
FORCEPROP 0 LASTPIN (2425 2950) $PN 228
J 2
(2415 2960);
DISPLAY 0.680851 (2415 2960);
PAINT MONO (2415 2960);
FORCEPROP 0 LASTPIN (2425 3000) $PN 230
J 2
(2415 3010);
DISPLAY 0.680851 (2415 3010);
PAINT MONO (2415 3010);
FORCEPROP 0 LASTPIN (2425 3050) $PN 233
J 2
(2415 3060);
DISPLAY 0.680851 (2415 3060);
PAINT MONO (2415 3060);
FORCEPROP 0 LASTPIN (2425 3100) $PN 235
J 2
(2415 3110);
DISPLAY 0.680851 (2415 3110);
PAINT MONO (2415 3110);
FORCEPROP 0 LASTPIN (2425 3150) $PN 237
J 2
(2415 3160);
DISPLAY 0.680851 (2415 3160);
PAINT MONO (2415 3160);
FORCEPROP 0 LASTPIN (2425 3200) $PN 240
J 2
(2415 3210);
DISPLAY 0.680851 (2415 3210);
PAINT MONO (2415 3210);
FORCEPROP 0 LASTPIN (2425 3250) $PN 242
J 2
(2415 3260);
DISPLAY 0.680851 (2415 3260);
PAINT MONO (2415 3260);
FORCEPROP 0 LASTPIN (2425 3300) $PN 244
J 2
(2415 3310);
DISPLAY 0.680851 (2415 3310);
PAINT MONO (2415 3310);
FORCEPROP 0 LASTPIN (2425 3350) $PN 246
J 2
(2415 3360);
DISPLAY 0.680851 (2415 3360);
PAINT MONO (2415 3360);
FORCEPROP 0 LASTPIN (2425 3400) $PN 248
J 2
(2415 3410);
DISPLAY 0.680851 (2415 3410);
PAINT MONO (2415 3410);
FORCEPROP 0 LASTPIN (2425 3450) $PN 251
J 2
(2415 3460);
DISPLAY 0.680851 (2415 3460);
PAINT MONO (2415 3460);
FORCEPROP 0 LASTPIN (2425 3500) $PN 253
J 2
(2415 3510);
DISPLAY 0.680851 (2415 3510);
PAINT MONO (2415 3510);
FORCEPROP 0 LASTPIN (2425 3550) $PN 255
J 2
(2415 3560);
DISPLAY 0.680851 (2415 3560);
PAINT MONO (2415 3560);
FORCEPROP 0 LASTPIN (2425 3600) $PN 257
J 2
(2415 3610);
DISPLAY 0.680851 (2415 3610);
PAINT MONO (2415 3610);
FORCEPROP 0 LASTPIN (2425 3650) $PN 259
J 2
(2415 3660);
DISPLAY 0.680851 (2415 3660);
PAINT MONO (2415 3660);
FORCEPROP 0 LASTPIN (2425 3700) $PN 262
J 2
(2415 3710);
DISPLAY 0.680851 (2415 3710);
PAINT MONO (2415 3710);
FORCEPROP 0 LASTPIN (2425 3750) $PN 264
J 2
(2415 3760);
DISPLAY 0.680851 (2415 3760);
PAINT MONO (2415 3760);
FORCEPROP 0 LASTPIN (2425 3800) $PN 266
J 2
(2415 3810);
DISPLAY 0.680851 (2415 3810);
PAINT MONO (2415 3810);
FORCEPROP 0 LASTPIN (2425 3850) $PN 268
J 2
(2415 3860);
DISPLAY 0.680851 (2415 3860);
PAINT MONO (2415 3860);
FORCEPROP 0 LASTPIN (2425 3900) $PN 270
J 2
(2415 3910);
DISPLAY 0.680851 (2415 3910);
PAINT MONO (2415 3910);
FORCEPROP 0 LASTPIN (2425 3950) $PN 273
J 2
(2415 3960);
DISPLAY 0.680851 (2415 3960);
PAINT MONO (2415 3960);
FORCEPROP 0 LASTPIN (2425 4000) $PN 275
J 2
(2415 4010);
DISPLAY 0.680851 (2415 4010);
PAINT MONO (2415 4010);
FORCEPROP 0 LASTPIN (2425 4050) $PN 277
J 2
(2415 4060);
DISPLAY 0.680851 (2415 4060);
PAINT MONO (2415 4060);
FORCEPROP 0 LASTPIN (2425 4100) $PN 279
J 2
(2415 4110);
DISPLAY 0.680851 (2415 4110);
PAINT MONO (2415 4110);
FORCEPROP 0 LASTPIN (2425 4150) $PN 281
J 2
(2415 4160);
DISPLAY 0.680851 (2415 4160);
PAINT MONO (2415 4160);
FORCEPROP 0 LASTPIN (2425 4200) $PN 284
J 2
(2415 4210);
DISPLAY 0.680851 (2415 4210);
PAINT MONO (2415 4210);
FORCEPROP 0 LASTPIN (2425 4250) $PN 286
J 2
(2415 4260);
DISPLAY 0.680851 (2415 4260);
PAINT MONO (2415 4260);
FORCEPROP 0 LASTPIN (2425 4300) $PN 288
J 2
(2415 4310);
DISPLAY 0.680851 (2415 4310);
PAINT MONO (2415 4310);
FORCEPROP 2 LAST CDS_LIB pure_quanta
J 0
(3025 2825);
DISPLAY INVISIBLE (3025 2825);
FORCEPROP 1 LAST CDS_LMAN_SYM_OUTLINE -450,1775,450,-1775
J 0
(3025 2825);
DISPLAY 0.468085 (3025 2825);
PAINT GREEN (3025 2825);
DISPLAY INVISIBLE (3025 2825);
FORCEPROP 1 LAST NEEDS_NO_SIZE TRUE
J 0
(3025 2825);
DISPLAY 0.723404 (3025 2825);
PAINT GREEN (3025 2825);
DISPLAY INVISIBLE (3025 2825);
FORCEPROP 1 LAST PATH I177
J 0
(3025 2825);
DISPLAY 0.723404 (3025 2825);
PAINT GREEN (3025 2825);
DISPLAY INVISIBLE (3025 2825);
FORCEPROP 2 LAST CDS_LOCATION J32
J 0
(2575 4950);
DISPLAY 1.021277 (2575 4950);
DISPLAY INVISIBLE (2575 4950);
FORCEPROP 0 LAST $SEC 3
J 0
(2575 4950);
DISPLAY 0.680851 (2575 4950);
PAINT MONO (2575 4950);
DISPLAY INVISIBLE (2575 4950);
FORCEPROP 2 LAST CDS_SEC 3
J 0
(2575 4950);
DISPLAY 1.021277 (2575 4950);
DISPLAY INVISIBLE (2575 4950);
FORCEADD SCONN288_ADR50017P087CC..1
(-3075 2725);
FORCEPROP 1 LAST PART_NUMBER DFHST8FS460
J 0
(-3520 4735);
DISPLAY 0.723404 (-3520 4735);
PAINT GREEN (-3520 4735);
DISPLAY INVISIBLE (-3520 4735);
FORCEPROP 1 LAST MATERIAL IO
J 0
(-3520 4608);
DISPLAY 0.723404 (-3520 4608);
PAINT GREEN (-3520 4608);
FORCEPROP 2 LAST VALUE SCONN288_ADR50017-P087CC
J 0
(-3525 4850);
DISPLAY 1.021277 (-3525 4850);
FORCEPROP 2 LAST PART_TYPE SMLF
J 0
(-3525 4925);
DISPLAY 1.021277 (-3525 4925);
FORCEPROP 1 LAST $LOCATION J32
J 0
(-3525 4800);
DISPLAY 0.723404 (-3525 4800);
PAINT GREEN (-3525 4800);
FORCEPROP 0 LASTPIN (-3675 2100) $PN 62
J 2
(-3685 2110);
DISPLAY 0.680851 (-3685 2110);
PAINT MONO (-3685 2110);
FORCEPROP 0 LASTPIN (-3675 4150) $PN 66
J 2
(-3685 4160);
DISPLAY 0.680851 (-3685 4160);
PAINT MONO (-3685 4160);
FORCEPROP 0 LASTPIN (-3675 3750) $PN 76
J 2
(-3685 3760);
DISPLAY 0.680851 (-3685 3760);
PAINT MONO (-3685 3760);
FORCEPROP 0 LASTPIN (-3675 4200) $PN 211
J 2
(-3685 4210);
DISPLAY 0.680851 (-3685 4210);
PAINT MONO (-3685 4210);
FORCEPROP 0 LASTPIN (-3675 3800) $PN 221
J 2
(-3685 3810);
DISPLAY 0.680851 (-3685 3810);
PAINT MONO (-3685 3810);
FORCEPROP 0 LASTPIN (-3675 4250) $PN 68
J 2
(-3685 4260);
DISPLAY 0.680851 (-3685 4260);
PAINT MONO (-3685 4260);
FORCEPROP 0 LASTPIN (-3675 3850) $PN 78
J 2
(-3685 3860);
DISPLAY 0.680851 (-3685 3860);
PAINT MONO (-3685 3860);
FORCEPROP 0 LASTPIN (-3675 4300) $PN 213
J 2
(-3685 4310);
DISPLAY 0.680851 (-3685 4310);
PAINT MONO (-3685 4310);
FORCEPROP 0 LASTPIN (-3675 3900) $PN 223
J 2
(-3685 3910);
DISPLAY 0.680851 (-3685 3910);
PAINT MONO (-3685 3910);
FORCEPROP 0 LASTPIN (-3675 4350) $PN 70
J 2
(-3685 4360);
DISPLAY 0.680851 (-3685 4360);
PAINT MONO (-3685 4360);
FORCEPROP 0 LASTPIN (-3675 3950) $PN 80
J 2
(-3685 3960);
DISPLAY 0.680851 (-3685 3960);
PAINT MONO (-3685 3960);
FORCEPROP 0 LASTPIN (-3675 4400) $PN 215
J 2
(-3685 4410);
DISPLAY 0.680851 (-3685 4410);
PAINT MONO (-3685 4410);
FORCEPROP 0 LASTPIN (-3675 4000) $PN 225
J 2
(-3685 4010);
DISPLAY 0.680851 (-3685 4010);
PAINT MONO (-3685 4010);
FORCEPROP 0 LASTPIN (-3675 4450) $PN 72
J 2
(-3685 4460);
DISPLAY 0.680851 (-3685 4460);
PAINT MONO (-3685 4460);
FORCEPROP 0 LASTPIN (-3675 4050) $PN 82
J 2
(-3685 4060);
DISPLAY 0.680851 (-3685 4060);
PAINT MONO (-3685 4060);
FORCEPROP 0 LASTPIN (-3675 2700) $PN 51
J 2
(-3685 2710);
DISPLAY 0.680851 (-3685 2710);
PAINT MONO (-3685 2710);
FORCEPROP 0 LASTPIN (-3675 2250) $PN 96
J 2
(-3685 2260);
DISPLAY 0.680851 (-3685 2260);
PAINT MONO (-3685 2260);
FORCEPROP 0 LASTPIN (-3675 2750) $PN 53
J 2
(-3685 2760);
DISPLAY 0.680851 (-3685 2760);
PAINT MONO (-3685 2760);
FORCEPROP 0 LASTPIN (-3675 2300) $PN 98
J 2
(-3685 2310);
DISPLAY 0.680851 (-3685 2310);
PAINT MONO (-3685 2310);
FORCEPROP 0 LASTPIN (-3675 2800) $PN 196
J 2
(-3685 2810);
DISPLAY 0.680851 (-3685 2810);
PAINT MONO (-3685 2810);
FORCEPROP 0 LASTPIN (-3675 2350) $PN 241
J 2
(-3685 2360);
DISPLAY 0.680851 (-3685 2360);
PAINT MONO (-3685 2360);
FORCEPROP 0 LASTPIN (-3675 2850) $PN 198
J 2
(-3685 2860);
DISPLAY 0.680851 (-3685 2860);
PAINT MONO (-3685 2860);
FORCEPROP 0 LASTPIN (-3675 2400) $PN 243
J 2
(-3685 2410);
DISPLAY 0.680851 (-3685 2410);
PAINT MONO (-3685 2410);
FORCEPROP 0 LASTPIN (-3675 2900) $PN 58
J 2
(-3685 2910);
DISPLAY 0.680851 (-3685 2910);
PAINT MONO (-3685 2910);
FORCEPROP 0 LASTPIN (-3675 2450) $PN 89
J 2
(-3685 2460);
DISPLAY 0.680851 (-3685 2460);
PAINT MONO (-3685 2460);
FORCEPROP 0 LASTPIN (-3675 2950) $PN 60
J 2
(-3685 2960);
DISPLAY 0.680851 (-3685 2960);
PAINT MONO (-3685 2960);
FORCEPROP 0 LASTPIN (-3675 2500) $PN 91
J 2
(-3685 2510);
DISPLAY 0.680851 (-3685 2510);
PAINT MONO (-3685 2510);
FORCEPROP 0 LASTPIN (-3675 3000) $PN 203
J 2
(-3685 3010);
DISPLAY 0.680851 (-3685 3010);
PAINT MONO (-3685 3010);
FORCEPROP 0 LASTPIN (-3675 2550) $PN 234
J 2
(-3685 2560);
DISPLAY 0.680851 (-3685 2560);
PAINT MONO (-3685 2560);
FORCEPROP 0 LASTPIN (-3675 3050) $PN 205
J 2
(-3685 3060);
DISPLAY 0.680851 (-3685 3060);
PAINT MONO (-3685 3060);
FORCEPROP 0 LASTPIN (-3675 2600) $PN 236
J 2
(-3685 2610);
DISPLAY 0.680851 (-3685 2610);
PAINT MONO (-3685 2610);
FORCEPROP 0 LASTPIN (-3675 3150) $PN 218
J 2
(-3685 3160);
DISPLAY 0.680851 (-3685 3160);
PAINT MONO (-3685 3160);
FORCEPROP 0 LASTPIN (-3675 3200) $PN 217
J 2
(-3685 3210);
DISPLAY 0.680851 (-3685 3210);
PAINT MONO (-3685 3210);
FORCEPROP 0 LASTPIN (-3675 3450) $PN 64
J 2
(-3685 3460);
DISPLAY 0.680851 (-3685 3460);
PAINT MONO (-3685 3460);
FORCEPROP 0 LASTPIN (-3675 3300) $PN 84
J 2
(-3685 3310);
DISPLAY 0.680851 (-3685 3310);
PAINT MONO (-3685 3310);
FORCEPROP 0 LASTPIN (-3675 3500) $PN 209
J 2
(-3685 3510);
DISPLAY 0.680851 (-3685 3510);
PAINT MONO (-3685 3510);
FORCEPROP 0 LASTPIN (-3675 3350) $PN 229
J 2
(-3685 3360);
DISPLAY 0.680851 (-3685 3360);
PAINT MONO (-3685 3360);
FORCEPROP 0 LASTPIN (-2475 2900) $PN 7
J 0
(-2465 2910);
DISPLAY 0.680851 (-2465 2910);
PAINT MONO (-2465 2910);
FORCEPROP 0 LASTPIN (-2475 1250) $PN 100
J 0
(-2465 1260);
DISPLAY 0.680851 (-2465 1260);
PAINT MONO (-2465 1260);
FORCEPROP 0 LASTPIN (-2475 2950) $PN 9
J 0
(-2465 2960);
DISPLAY 0.680851 (-2465 2960);
PAINT MONO (-2465 2960);
FORCEPROP 0 LASTPIN (-2475 1300) $PN 102
J 0
(-2465 1310);
DISPLAY 0.680851 (-2465 1310);
PAINT MONO (-2465 1310);
FORCEPROP 0 LASTPIN (-2475 3000) $PN 152
J 0
(-2465 3010);
DISPLAY 0.680851 (-2465 3010);
PAINT MONO (-2465 3010);
FORCEPROP 0 LASTPIN (-2475 1350) $PN 245
J 0
(-2465 1360);
DISPLAY 0.680851 (-2465 1360);
PAINT MONO (-2465 1360);
FORCEPROP 0 LASTPIN (-2475 3050) $PN 154
J 0
(-2465 3060);
DISPLAY 0.680851 (-2465 3060);
PAINT MONO (-2465 3060);
FORCEPROP 0 LASTPIN (-2475 1400) $PN 247
J 0
(-2465 1410);
DISPLAY 0.680851 (-2465 1410);
PAINT MONO (-2465 1410);
FORCEPROP 0 LASTPIN (-2475 3100) $PN 14
J 0
(-2465 3110);
DISPLAY 0.680851 (-2465 3110);
PAINT MONO (-2465 3110);
FORCEPROP 0 LASTPIN (-2475 1450) $PN 107
J 0
(-2465 1460);
DISPLAY 0.680851 (-2465 1460);
PAINT MONO (-2465 1460);
FORCEPROP 0 LASTPIN (-2475 3150) $PN 16
J 0
(-2465 3160);
DISPLAY 0.680851 (-2465 3160);
PAINT MONO (-2465 3160);
FORCEPROP 0 LASTPIN (-2475 1500) $PN 109
J 0
(-2465 1510);
DISPLAY 0.680851 (-2465 1510);
PAINT MONO (-2465 1510);
FORCEPROP 0 LASTPIN (-2475 3200) $PN 159
J 0
(-2465 3210);
DISPLAY 0.680851 (-2465 3210);
PAINT MONO (-2465 3210);
FORCEPROP 0 LASTPIN (-2475 1550) $PN 252
J 0
(-2465 1560);
DISPLAY 0.680851 (-2465 1560);
PAINT MONO (-2465 1560);
FORCEPROP 0 LASTPIN (-2475 3250) $PN 161
J 0
(-2465 3260);
DISPLAY 0.680851 (-2465 3260);
PAINT MONO (-2465 3260);
FORCEPROP 0 LASTPIN (-2475 1600) $PN 254
J 0
(-2465 1610);
DISPLAY 0.680851 (-2465 1610);
PAINT MONO (-2465 1610);
FORCEPROP 0 LASTPIN (-2475 3300) $PN 18
J 0
(-2465 3310);
DISPLAY 0.680851 (-2465 3310);
PAINT MONO (-2465 3310);
FORCEPROP 0 LASTPIN (-2475 1650) $PN 111
J 0
(-2465 1660);
DISPLAY 0.680851 (-2465 1660);
PAINT MONO (-2465 1660);
FORCEPROP 0 LASTPIN (-2475 3350) $PN 20
J 0
(-2465 3360);
DISPLAY 0.680851 (-2465 3360);
PAINT MONO (-2465 3360);
FORCEPROP 0 LASTPIN (-2475 1700) $PN 113
J 0
(-2465 1710);
DISPLAY 0.680851 (-2465 1710);
PAINT MONO (-2465 1710);
FORCEPROP 0 LASTPIN (-2475 3400) $PN 163
J 0
(-2465 3410);
DISPLAY 0.680851 (-2465 3410);
PAINT MONO (-2465 3410);
FORCEPROP 0 LASTPIN (-2475 1750) $PN 256
J 0
(-2465 1760);
DISPLAY 0.680851 (-2465 1760);
PAINT MONO (-2465 1760);
FORCEPROP 0 LASTPIN (-2475 3450) $PN 165
J 0
(-2465 3460);
DISPLAY 0.680851 (-2465 3460);
PAINT MONO (-2465 3460);
FORCEPROP 0 LASTPIN (-2475 1800) $PN 258
J 0
(-2465 1810);
DISPLAY 0.680851 (-2465 1810);
PAINT MONO (-2465 1810);
FORCEPROP 0 LASTPIN (-2475 3500) $PN 25
J 0
(-2465 3510);
DISPLAY 0.680851 (-2465 3510);
PAINT MONO (-2465 3510);
FORCEPROP 0 LASTPIN (-2475 1850) $PN 118
J 0
(-2465 1860);
DISPLAY 0.680851 (-2465 1860);
PAINT MONO (-2465 1860);
FORCEPROP 0 LASTPIN (-2475 3550) $PN 27
J 0
(-2465 3560);
DISPLAY 0.680851 (-2465 3560);
PAINT MONO (-2465 3560);
FORCEPROP 0 LASTPIN (-2475 1900) $PN 120
J 0
(-2465 1910);
DISPLAY 0.680851 (-2465 1910);
PAINT MONO (-2465 1910);
FORCEPROP 0 LASTPIN (-2475 3600) $PN 170
J 0
(-2465 3610);
DISPLAY 0.680851 (-2465 3610);
PAINT MONO (-2465 3610);
FORCEPROP 0 LASTPIN (-2475 1950) $PN 263
J 0
(-2465 1960);
DISPLAY 0.680851 (-2465 1960);
PAINT MONO (-2465 1960);
FORCEPROP 0 LASTPIN (-2475 3650) $PN 172
J 0
(-2465 3660);
DISPLAY 0.680851 (-2465 3660);
PAINT MONO (-2465 3660);
FORCEPROP 0 LASTPIN (-2475 2000) $PN 265
J 0
(-2465 2010);
DISPLAY 0.680851 (-2465 2010);
PAINT MONO (-2465 2010);
FORCEPROP 0 LASTPIN (-2475 3700) $PN 29
J 0
(-2465 3710);
DISPLAY 0.680851 (-2465 3710);
PAINT MONO (-2465 3710);
FORCEPROP 0 LASTPIN (-2475 2050) $PN 122
J 0
(-2465 2060);
DISPLAY 0.680851 (-2465 2060);
PAINT MONO (-2465 2060);
FORCEPROP 0 LASTPIN (-2475 3750) $PN 31
J 0
(-2465 3760);
DISPLAY 0.680851 (-2465 3760);
PAINT MONO (-2465 3760);
FORCEPROP 0 LASTPIN (-2475 2100) $PN 124
J 0
(-2465 2110);
DISPLAY 0.680851 (-2465 2110);
PAINT MONO (-2465 2110);
FORCEPROP 0 LASTPIN (-2475 3800) $PN 174
J 0
(-2465 3810);
DISPLAY 0.680851 (-2465 3810);
PAINT MONO (-2465 3810);
FORCEPROP 0 LASTPIN (-2475 2150) $PN 267
J 0
(-2465 2160);
DISPLAY 0.680851 (-2465 2160);
PAINT MONO (-2465 2160);
FORCEPROP 0 LASTPIN (-2475 3850) $PN 176
J 0
(-2465 3860);
DISPLAY 0.680851 (-2465 3860);
PAINT MONO (-2465 3860);
FORCEPROP 0 LASTPIN (-2475 2200) $PN 269
J 0
(-2465 2210);
DISPLAY 0.680851 (-2465 2210);
PAINT MONO (-2465 2210);
FORCEPROP 0 LASTPIN (-2475 3900) $PN 36
J 0
(-2465 3910);
DISPLAY 0.680851 (-2465 3910);
PAINT MONO (-2465 3910);
FORCEPROP 0 LASTPIN (-2475 2250) $PN 129
J 0
(-2465 2260);
DISPLAY 0.680851 (-2465 2260);
PAINT MONO (-2465 2260);
FORCEPROP 0 LASTPIN (-2475 3950) $PN 38
J 0
(-2465 3960);
DISPLAY 0.680851 (-2465 3960);
PAINT MONO (-2465 3960);
FORCEPROP 0 LASTPIN (-2475 2300) $PN 131
J 0
(-2465 2310);
DISPLAY 0.680851 (-2465 2310);
PAINT MONO (-2465 2310);
FORCEPROP 0 LASTPIN (-2475 4000) $PN 181
J 0
(-2465 4010);
DISPLAY 0.680851 (-2465 4010);
PAINT MONO (-2465 4010);
FORCEPROP 0 LASTPIN (-2475 2350) $PN 274
J 0
(-2465 2360);
DISPLAY 0.680851 (-2465 2360);
PAINT MONO (-2465 2360);
FORCEPROP 0 LASTPIN (-2475 4050) $PN 183
J 0
(-2465 4060);
DISPLAY 0.680851 (-2465 4060);
PAINT MONO (-2465 4060);
FORCEPROP 0 LASTPIN (-2475 2400) $PN 276
J 0
(-2465 2410);
DISPLAY 0.680851 (-2465 2410);
PAINT MONO (-2465 2410);
FORCEPROP 0 LASTPIN (-2475 4100) $PN 40
J 0
(-2465 4110);
DISPLAY 0.680851 (-2465 4110);
PAINT MONO (-2465 4110);
FORCEPROP 0 LASTPIN (-2475 2450) $PN 133
J 0
(-2465 2460);
DISPLAY 0.680851 (-2465 2460);
PAINT MONO (-2465 2460);
FORCEPROP 0 LASTPIN (-2475 4150) $PN 42
J 0
(-2465 4160);
DISPLAY 0.680851 (-2465 4160);
PAINT MONO (-2465 4160);
FORCEPROP 0 LASTPIN (-2475 2500) $PN 135
J 0
(-2465 2510);
DISPLAY 0.680851 (-2465 2510);
PAINT MONO (-2465 2510);
FORCEPROP 0 LASTPIN (-2475 4200) $PN 185
J 0
(-2465 4210);
DISPLAY 0.680851 (-2465 4210);
PAINT MONO (-2465 4210);
FORCEPROP 0 LASTPIN (-2475 2550) $PN 278
J 0
(-2465 2560);
DISPLAY 0.680851 (-2465 2560);
PAINT MONO (-2465 2560);
FORCEPROP 0 LASTPIN (-2475 4250) $PN 187
J 0
(-2465 4260);
DISPLAY 0.680851 (-2465 4260);
PAINT MONO (-2465 4260);
FORCEPROP 0 LASTPIN (-2475 2600) $PN 280
J 0
(-2465 2610);
DISPLAY 0.680851 (-2465 2610);
PAINT MONO (-2465 2610);
FORCEPROP 0 LASTPIN (-2475 4300) $PN 47
J 0
(-2465 4310);
DISPLAY 0.680851 (-2465 4310);
PAINT MONO (-2465 4310);
FORCEPROP 0 LASTPIN (-2475 2650) $PN 140
J 0
(-2465 2660);
DISPLAY 0.680851 (-2465 2660);
PAINT MONO (-2465 2660);
FORCEPROP 0 LASTPIN (-2475 4350) $PN 49
J 0
(-2465 4360);
DISPLAY 0.680851 (-2465 4360);
PAINT MONO (-2465 4360);
FORCEPROP 0 LASTPIN (-2475 2700) $PN 142
J 0
(-2465 2710);
DISPLAY 0.680851 (-2465 2710);
PAINT MONO (-2465 2710);
FORCEPROP 0 LASTPIN (-2475 4400) $PN 192
J 0
(-2465 4410);
DISPLAY 0.680851 (-2465 4410);
PAINT MONO (-2465 4410);
FORCEPROP 0 LASTPIN (-2475 2750) $PN 285
J 0
(-2465 2760);
DISPLAY 0.680851 (-2465 2760);
PAINT MONO (-2465 2760);
FORCEPROP 0 LASTPIN (-2475 4450) $PN 194
J 0
(-2465 4460);
DISPLAY 0.680851 (-2465 4460);
PAINT MONO (-2465 4460);
FORCEPROP 0 LASTPIN (-2475 2800) $PN 287
J 0
(-2465 2810);
DISPLAY 0.680851 (-2465 2810);
PAINT MONO (-2465 2810);
FORCEPROP 0 LASTPIN (-3675 1950) $PN 148
J 2
(-3685 1960);
DISPLAY 0.680851 (-3685 1960);
PAINT MONO (-3685 1960);
FORCEPROP 0 LASTPIN (-3675 1850) $PN 4
J 2
(-3685 1860);
DISPLAY 0.680851 (-3685 1860);
PAINT MONO (-3685 1860);
FORCEPROP 0 LASTPIN (-3675 1900) $PN 5
J 2
(-3685 1910);
DISPLAY 0.680851 (-3685 1910);
PAINT MONO (-3685 1910);
FORCEPROP 0 LASTPIN (-3675 1050) $PN 86
J 2
(-3685 1060);
DISPLAY 0.680851 (-3685 1060);
PAINT MONO (-3685 1060);
FORCEPROP 0 LASTPIN (-3675 1000) $PN 87
J 2
(-3685 1010);
DISPLAY 0.680851 (-3685 1010);
PAINT MONO (-3685 1010);
FORCEPROP 0 LASTPIN (-3675 3650) $PN 74
J 2
(-3685 3660);
DISPLAY 0.680851 (-3685 3660);
PAINT MONO (-3685 3660);
FORCEPROP 0 LASTPIN (-3675 3600) $PN 227
J 2
(-3685 3610);
DISPLAY 0.680851 (-3685 3610);
PAINT MONO (-3685 3610);
FORCEPROP 0 LASTPIN (-3675 1600) $PN 147
J 2
(-3685 1610);
DISPLAY 0.680851 (-3685 1610);
PAINT MONO (-3685 1610);
FORCEPROP 0 LASTPIN (-3675 2150) $PN 207
J 2
(-3685 2160);
DISPLAY 0.680851 (-3685 2160);
PAINT MONO (-3685 2160);
FORCEPROP 0 LASTPIN (-3675 1200) $PN 2
J 2
(-3685 1210);
DISPLAY 0.680851 (-3685 1210);
PAINT MONO (-3685 1210);
FORCEPROP 0 LASTPIN (-3675 1250) $PN 144
J 2
(-3685 1260);
DISPLAY 0.680851 (-3685 1260);
PAINT MONO (-3685 1260);
FORCEPROP 0 LASTPIN (-3675 1300) $PN 149
J 2
(-3685 1310);
DISPLAY 0.680851 (-3685 1310);
PAINT MONO (-3685 1310);
FORCEPROP 0 LASTPIN (-3675 1350) $PN 150
J 2
(-3685 1360);
DISPLAY 0.680851 (-3685 1360);
PAINT MONO (-3685 1360);
FORCEPROP 0 LASTPIN (-3675 1400) $PN 220
J 2
(-3685 1410);
DISPLAY 0.680851 (-3685 1410);
PAINT MONO (-3685 1410);
FORCEPROP 0 LASTPIN (-3675 1450) $PN 231
J 2
(-3685 1460);
DISPLAY 0.680851 (-3685 1460);
PAINT MONO (-3685 1460);
FORCEPROP 0 LASTPIN (-3675 1500) $PN 232
J 2
(-3685 1510);
DISPLAY 0.680851 (-3685 1510);
PAINT MONO (-3685 1510);
FORCEPROP 0 LASTPIN (-3675 2000) $PN 3
J 2
(-3685 2010);
DISPLAY 0.680851 (-3685 2010);
PAINT MONO (-3685 2010);
FORCEPROP 2 LAST CDS_LIB pure_quanta
J 0
(-3075 2725);
DISPLAY INVISIBLE (-3075 2725);
FORCEPROP 1 LAST CDS_LMAN_SYM_OUTLINE -450,1875,450,-1875
J 0
(-3075 2725);
DISPLAY 0.468085 (-3075 2725);
PAINT GREEN (-3075 2725);
DISPLAY INVISIBLE (-3075 2725);
FORCEPROP 1 LAST NEEDS_NO_SIZE TRUE
J 0
(-3075 2725);
DISPLAY 0.723404 (-3075 2725);
PAINT GREEN (-3075 2725);
DISPLAY INVISIBLE (-3075 2725);
FORCEPROP 1 LAST PATH I179
J 0
(-3075 2725);
DISPLAY 0.723404 (-3075 2725);
PAINT GREEN (-3075 2725);
DISPLAY INVISIBLE (-3075 2725);
FORCEPROP 2 LAST CDS_LOCATION J32
J 0
(-3525 4950);
DISPLAY 1.021277 (-3525 4950);
DISPLAY INVISIBLE (-3525 4950);
FORCEPROP 0 LAST $SEC 1
J 0
(-3525 4950);
DISPLAY 0.680851 (-3525 4950);
PAINT MONO (-3525 4950);
DISPLAY INVISIBLE (-3525 4950);
FORCEPROP 2 LAST CDS_SEC 1
J 0
(-3525 4950);
DISPLAY 1.021277 (-3525 4950);
DISPLAY INVISIBLE (-3525 4950);
FORCEADD OFFPAGE..1
(-4825 3600);
FORCEPROP 2 LAST $XR1 112 
J 0
(-5166 3600);
DISPLAY 0.638298 (-5166 3600);
PAINT MONO (-5166 3600);
FORCEPROP 2 LAST $XR0 58 
J 0
(-5046 3600);
DISPLAY 0.638298 (-5046 3600);
PAINT MONO (-5046 3600);
FORCEPROP 2 LAST CDS_LIB standard
J 0
(-4825 3600);
PAINT MONO (-4825 3600);
DISPLAY INVISIBLE (-4825 3600);
FORCEPROP 1 LAST OFFPAGE TRUE
J 0
(-4500 3475);
DISPLAY 0.872340 (-4500 3475);
DISPLAY INVISIBLE (-4500 3475);
FORCEPROP 1 LAST COMMENT_BODY TRUE
J 0
(-4700 3500);
DISPLAY 0.872340 (-4700 3500);
PAINT GREEN (-4700 3500);
DISPLAY INVISIBLE (-4700 3500);
FORCEPROP 2 LAST PATH I18
J 0
(-4775 3675);
DISPLAY 1.021277 (-4775 3675);
DISPLAY INVISIBLE (-4775 3675);
FORCEADD SCONN288_ADR50017P087CC..2
(-400 3450);
FORCEPROP 1 LAST PART_NUMBER DFHST8FS460
J 0
(-1005 4738);
DISPLAY 0.723404 (-1005 4738);
PAINT GREEN (-1005 4738);
DISPLAY INVISIBLE (-1005 4738);
FORCEPROP 2 LAST VALUE SCONN288_ADR50017-P087CC
J 0
(-1000 4925);
DISPLAY 1.021277 (-1000 4925);
FORCEPROP 1 LAST MATERIAL IO
J 0
(-1005 4611);
DISPLAY 0.723404 (-1005 4611);
PAINT GREEN (-1005 4611);
FORCEPROP 2 LAST PART_TYPE SMLF
J 0
(-1000 4975);
DISPLAY 1.021277 (-1000 4975);
FORCEPROP 1 LAST LOCATION J32
J 0
(-1005 4885);
DISPLAY 0.723404 (-1005 4885);
PAINT GREEN (-1005 4885);
FORCEPROP 0 LASTPIN (350 3500) $PN 12
J 0
(360 3510);
DISPLAY 0.680851 (360 3510);
PAINT MONO (360 3510);
FORCEPROP 0 LASTPIN (350 3550) $PN 11
J 0
(360 3560);
DISPLAY 0.680851 (360 3560);
PAINT MONO (360 3560);
FORCEPROP 0 LASTPIN (350 2450) $PN 105
J 0
(360 2460);
DISPLAY 0.680851 (360 2460);
PAINT MONO (360 2460);
FORCEPROP 0 LASTPIN (350 2500) $PN 104
J 0
(360 2510);
DISPLAY 0.680851 (360 2510);
PAINT MONO (360 2510);
FORCEPROP 0 LASTPIN (350 3600) $PN 23
J 0
(360 3610);
DISPLAY 0.680851 (360 3610);
PAINT MONO (360 3610);
FORCEPROP 0 LASTPIN (350 3650) $PN 22
J 0
(360 3660);
DISPLAY 0.680851 (360 3660);
PAINT MONO (360 3660);
FORCEPROP 0 LASTPIN (350 2550) $PN 116
J 0
(360 2560);
DISPLAY 0.680851 (360 2560);
PAINT MONO (360 2560);
FORCEPROP 0 LASTPIN (350 2600) $PN 115
J 0
(360 2610);
DISPLAY 0.680851 (360 2610);
PAINT MONO (360 2610);
FORCEPROP 0 LASTPIN (350 3700) $PN 34
J 0
(360 3710);
DISPLAY 0.680851 (360 3710);
PAINT MONO (360 3710);
FORCEPROP 0 LASTPIN (350 3750) $PN 33
J 0
(360 3760);
DISPLAY 0.680851 (360 3760);
PAINT MONO (360 3760);
FORCEPROP 0 LASTPIN (350 2650) $PN 127
J 0
(360 2660);
DISPLAY 0.680851 (360 2660);
PAINT MONO (360 2660);
FORCEPROP 0 LASTPIN (350 2700) $PN 126
J 0
(360 2710);
DISPLAY 0.680851 (360 2710);
PAINT MONO (360 2710);
FORCEPROP 0 LASTPIN (350 3800) $PN 45
J 0
(360 3810);
DISPLAY 0.680851 (360 3810);
PAINT MONO (360 3810);
FORCEPROP 0 LASTPIN (350 3850) $PN 44
J 0
(360 3860);
DISPLAY 0.680851 (360 3860);
PAINT MONO (360 3860);
FORCEPROP 0 LASTPIN (350 2750) $PN 138
J 0
(360 2760);
DISPLAY 0.680851 (360 2760);
PAINT MONO (360 2760);
FORCEPROP 0 LASTPIN (350 2800) $PN 137
J 0
(360 2810);
DISPLAY 0.680851 (360 2810);
PAINT MONO (360 2810);
FORCEPROP 0 LASTPIN (350 3900) $PN 56
J 0
(360 3910);
DISPLAY 0.680851 (360 3910);
PAINT MONO (360 3910);
FORCEPROP 0 LASTPIN (350 3950) $PN 55
J 0
(360 3960);
DISPLAY 0.680851 (360 3960);
PAINT MONO (360 3960);
FORCEPROP 0 LASTPIN (350 2850) $PN 238
J 0
(360 2860);
DISPLAY 0.680851 (360 2860);
PAINT MONO (360 2860);
FORCEPROP 0 LASTPIN (350 2900) $PN 239
J 0
(360 2910);
DISPLAY 0.680851 (360 2910);
PAINT MONO (360 2910);
FORCEPROP 0 LASTPIN (350 4000) $PN 156
J 0
(360 4010);
DISPLAY 0.680851 (360 4010);
PAINT MONO (360 4010);
FORCEPROP 0 LASTPIN (350 4050) $PN 157
J 0
(360 4060);
DISPLAY 0.680851 (360 4060);
PAINT MONO (360 4060);
FORCEPROP 0 LASTPIN (350 2950) $PN 249
J 0
(360 2960);
DISPLAY 0.680851 (360 2960);
PAINT MONO (360 2960);
FORCEPROP 0 LASTPIN (350 3000) $PN 250
J 0
(360 3010);
DISPLAY 0.680851 (360 3010);
PAINT MONO (360 3010);
FORCEPROP 0 LASTPIN (350 4100) $PN 167
J 0
(360 4110);
DISPLAY 0.680851 (360 4110);
PAINT MONO (360 4110);
FORCEPROP 0 LASTPIN (350 4150) $PN 168
J 0
(360 4160);
DISPLAY 0.680851 (360 4160);
PAINT MONO (360 4160);
FORCEPROP 0 LASTPIN (350 3050) $PN 260
J 0
(360 3060);
DISPLAY 0.680851 (360 3060);
PAINT MONO (360 3060);
FORCEPROP 0 LASTPIN (350 3100) $PN 261
J 0
(360 3110);
DISPLAY 0.680851 (360 3110);
PAINT MONO (360 3110);
FORCEPROP 0 LASTPIN (350 4200) $PN 178
J 0
(360 4210);
DISPLAY 0.680851 (360 4210);
PAINT MONO (360 4210);
FORCEPROP 0 LASTPIN (350 4250) $PN 179
J 0
(360 4260);
DISPLAY 0.680851 (360 4260);
PAINT MONO (360 4260);
FORCEPROP 0 LASTPIN (350 3150) $PN 271
J 0
(360 3160);
DISPLAY 0.680851 (360 3160);
PAINT MONO (360 3160);
FORCEPROP 0 LASTPIN (350 3200) $PN 272
J 0
(360 3210);
DISPLAY 0.680851 (360 3210);
PAINT MONO (360 3210);
FORCEPROP 0 LASTPIN (350 4300) $PN 189
J 0
(360 4310);
DISPLAY 0.680851 (360 4310);
PAINT MONO (360 4310);
FORCEPROP 0 LASTPIN (350 4350) $PN 190
J 0
(360 4360);
DISPLAY 0.680851 (360 4360);
PAINT MONO (360 4360);
FORCEPROP 0 LASTPIN (350 3250) $PN 282
J 0
(360 3260);
DISPLAY 0.680851 (360 3260);
PAINT MONO (360 3260);
FORCEPROP 0 LASTPIN (350 3300) $PN 283
J 0
(360 3310);
DISPLAY 0.680851 (360 3310);
PAINT MONO (360 3310);
FORCEPROP 0 LASTPIN (350 4400) $PN 200
J 0
(360 4410);
DISPLAY 0.680851 (360 4410);
PAINT MONO (360 4410);
FORCEPROP 0 LASTPIN (350 4450) $PN 201
J 0
(360 4460);
DISPLAY 0.680851 (360 4460);
PAINT MONO (360 4460);
FORCEPROP 0 LASTPIN (350 3350) $PN 94
J 0
(360 3360);
DISPLAY 0.680851 (360 3360);
PAINT MONO (360 3360);
FORCEPROP 0 LASTPIN (350 3400) $PN 93
J 0
(360 3410);
DISPLAY 0.680851 (360 3410);
PAINT MONO (360 3410);
FORCEPROP 2 LAST CDS_LIB pure_quanta
J 0
(-400 3450);
DISPLAY INVISIBLE (-400 3450);
FORCEPROP 1 LAST CDS_LMAN_SYM_OUTLINE -600,1150,600,-1150
J 0
(-400 3450);
DISPLAY 0.468085 (-400 3450);
PAINT GREEN (-400 3450);
DISPLAY INVISIBLE (-400 3450);
FORCEPROP 1 LAST NEEDS_NO_SIZE TRUE
J 0
(-400 3450);
DISPLAY 0.723404 (-400 3450);
PAINT GREEN (-400 3450);
DISPLAY INVISIBLE (-400 3450);
FORCEPROP 1 LAST PATH I180
J 0
(-400 3450);
DISPLAY 0.723404 (-400 3450);
PAINT GREEN (-400 3450);
DISPLAY INVISIBLE (-400 3450);
FORCEPROP 0 LAST $SEC 2
J 0
(-1000 5025);
DISPLAY 0.680851 (-1000 5025);
PAINT MONO (-1000 5025);
DISPLAY INVISIBLE (-1000 5025);
FORCEPROP 0 LAST CDS_SEC 2
J 0
(-1000 5025);
DISPLAY 1.021277 (-1000 5025);
DISPLAY INVISIBLE (-1000 5025);
FORCEADD OFFPAGE..1
(-3650 1675);
FORCEPROP 2 LAST $XR7 112 
J 0
(-4772 1675);
DISPLAY 0.638298 (-4772 1675);
PAINT MONO (-4772 1675);
FORCEPROP 2 LAST $XR6 111 
J 0
(-4652 1675);
DISPLAY 0.638298 (-4652 1675);
PAINT MONO (-4652 1675);
FORCEPROP 2 LAST $XR5 110 
J 0
(-4532 1675);
DISPLAY 0.638298 (-4532 1675);
PAINT MONO (-4532 1675);
FORCEPROP 2 LAST $XR4 109 
J 0
(-4412 1675);
DISPLAY 0.638298 (-4412 1675);
PAINT MONO (-4412 1675);
FORCEPROP 2 LAST $XR3 108 
J 0
(-4292 1675);
DISPLAY 0.638298 (-4292 1675);
PAINT MONO (-4292 1675);
FORCEPROP 2 LAST $XR2 107 
J 0
(-4172 1675);
DISPLAY 0.638298 (-4172 1675);
PAINT MONO (-4172 1675);
FORCEPROP 2 LAST $XR1 106 
J 0
(-4052 1675);
DISPLAY 0.638298 (-4052 1675);
PAINT MONO (-4052 1675);
FORCEPROP 2 LAST $XR0 230 
J 0
(-3932 1675);
DISPLAY 0.638298 (-3932 1675);
PAINT MONO (-3932 1675);
FORCEPROP 2 LAST CDS_LIB standard
J 2
(-3650 1675);
DISPLAY INVISIBLE (-3650 1675);
FORCEPROP 1 LAST OFFPAGE TRUE
J 0
(-3325 1550);
DISPLAY 0.872340 (-3325 1550);
DISPLAY INVISIBLE (-3325 1550);
FORCEPROP 1 LAST COMMENT_BODY TRUE
J 0
(-3525 1575);
DISPLAY 0.872340 (-3525 1575);
PAINT GREEN (-3525 1575);
DISPLAY INVISIBLE (-3525 1575);
FORCEPROP 2 LAST PATH I181
J 2
(-3825 1750);
DISPLAY 1.021277 (-3825 1750);
DISPLAY INVISIBLE (-3825 1750);
FORCEADD Q_RES..1
(-4900 1750);
FORCEPROP 1 LAST PART_NUMBER CS04992FB07
J 0
(-4800 1725);
DISPLAY 0.404255 (-4800 1725);
DISPLAY INVISIBLE (-4800 1725);
FORCEPROP 1 LAST VALUE 49.9
J 2
(-4675 1750);
DISPLAY 0.510638 (-4675 1750);
FORCEPROP 1 LAST MATERIAL CHIP
J 0
(-5050 1700);
DISPLAY 0.404255 (-5050 1700);
FORCEPROP 1 LAST $LOCATION R3906
J 0
(-5125 1750);
DISPLAY 0.638298 (-5125 1750);
FORCEPROP 1 LASTPIN (-5000 1750) $PN 1
J 0
(-4988 1762);
DISPLAY 0.787234 (-4988 1762);
PAINT MONO (-4988 1762);
FORCEPROP 1 LASTPIN (-4800 1750) $PN 2
J 0
(-4838 1762);
DISPLAY 0.787234 (-4838 1762);
PAINT MONO (-4838 1762);
FORCEPROP 2 LAST CDS_LIB pure_quanta
J 0
(-4900 1750);
DISPLAY INVISIBLE (-4900 1750);
FORCEPROP 1 LAST PACK_TYPE 0402LF
J 0
(-4600 1750);
DISPLAY 0.510638 (-4600 1750);
DISPLAY INVISIBLE (-4600 1750);
FORCEPROP 1 LAST TOLERANCE 1%
J 0
(-4675 1750);
DISPLAY 0.510638 (-4675 1750);
DISPLAY INVISIBLE (-4675 1750);
FORCEPROP 1 LAST WATTAGE 1/16W
J 2
(-4600 1700);
DISPLAY 0.404255 (-4600 1700);
DISPLAY INVISIBLE (-4600 1700);
FORCEPROP 1 LAST PATH I182
J 0
(-4950 1900);
DISPLAY 0.978723 (-4950 1900);
PAINT WHITE (-4950 1900);
DISPLAY INVISIBLE (-4950 1900);
FORCEPROP 0 LAST CDS_LOCATION R3906
J 0
(-5050 1800);
DISPLAY 1.021277 (-5050 1800);
DISPLAY INVISIBLE (-5050 1800);
FORCEPROP 0 LAST $SEC 1
J 0
(-5050 1800);
DISPLAY 0.680851 (-5050 1800);
PAINT MONO (-5050 1800);
DISPLAY INVISIBLE (-5050 1800);
FORCEPROP 0 LAST CDS_SEC 1
J 0
(-5050 1800);
DISPLAY 1.021277 (-5050 1800);
DISPLAY INVISIBLE (-5050 1800);
FORCEADD OFFPAGE..1
(-4825 3650);
FORCEPROP 2 LAST $XR1 112 
J 0
(-5166 3650);
DISPLAY 0.638298 (-5166 3650);
PAINT MONO (-5166 3650);
FORCEPROP 2 LAST $XR0 58 
J 0
(-5046 3650);
DISPLAY 0.638298 (-5046 3650);
PAINT MONO (-5046 3650);
FORCEPROP 2 LAST CDS_LIB standard
J 0
(-4825 3650);
PAINT MONO (-4825 3650);
DISPLAY INVISIBLE (-4825 3650);
FORCEPROP 1 LAST OFFPAGE TRUE
J 0
(-4500 3525);
DISPLAY 0.872340 (-4500 3525);
DISPLAY INVISIBLE (-4500 3525);
FORCEPROP 1 LAST COMMENT_BODY TRUE
J 0
(-4700 3550);
DISPLAY 0.872340 (-4700 3550);
PAINT GREEN (-4700 3550);
DISPLAY INVISIBLE (-4700 3550);
FORCEPROP 2 LAST PATH I19
J 0
(-4775 3725);
DISPLAY 1.021277 (-4775 3725);
DISPLAY INVISIBLE (-4775 3725);
FORCEADD Q_RES..2
(-3675 300);
FORCEPROP 1 LAST PART_NUMBER CS41962FB03
J 0
(-3635 175);
DISPLAY 0.978723 (-3635 175);
DISPLAY INVISIBLE (-3635 175);
FORCEPROP 1 LAST MATERIAL CHIP
J 0
(-3635 225);
DISPLAY 0.978723 (-3635 225);
FORCEPROP 1 LAST PACK_TYPE 0402LF
J 0
(-3635 125);
DISPLAY 0.978723 (-3635 125);
FORCEPROP 1 LAST WATTAGE 1/16W
J 0
(-3635 275);
DISPLAY 0.978723 (-3635 275);
FORCEPROP 1 LAST TOLERANCE 1%
J 0
(-3630 325);
DISPLAY 0.978723 (-3630 325);
FORCEPROP 1 LAST VALUE 196K
J 0
(-3630 375);
DISPLAY 0.978723 (-3630 375);
FORCEPROP 1 LAST $LOCATION R72
J 0
(-3630 425);
DISPLAY 0.978723 (-3630 425);
FORCEPROP 1 LASTPIN (-3675 400) $PN 1
J 0
(-3670 362);
DISPLAY 0.787234 (-3670 362);
FORCEPROP 1 LASTPIN (-3675 200) $PN 2
J 0
(-3670 210);
DISPLAY 0.787234 (-3670 210);
FORCEPROP 2 LAST CDS_LIB pure_quanta
J 0
(-3675 300);
PAINT MONO (-3675 300);
DISPLAY INVISIBLE (-3675 300);
FORCEPROP 1 LAST PATH I2
J 0
(-3625 475);
DISPLAY 0.978723 (-3625 475);
PAINT WHITE (-3625 475);
DISPLAY INVISIBLE (-3625 475);
FORCEPROP 1 LAST $LOCATION R72
J 0
(-3625 525);
DISPLAY 1.021277 (-3625 525);
DISPLAY INVISIBLE (-3625 525);
FORCEPROP 2 LAST CDS_LOCATION R72
J 0
(-3625 525);
DISPLAY 1.021277 (-3625 525);
DISPLAY INVISIBLE (-3625 525);
FORCEPROP 2 LAST $SEC 1
J 0
(-3625 525);
DISPLAY 0.680851 (-3625 525);
PAINT MONO (-3625 525);
DISPLAY INVISIBLE (-3625 525);
FORCEPROP 2 LAST CDS_SEC 1
J 0
(-3625 525);
DISPLAY 1.021277 (-3625 525);
DISPLAY INVISIBLE (-3625 525);
FORCEADD OFFPAGE..1
(-4825 3450);
FORCEPROP 2 LAST $XR0 58 
J 0
(-5046 3450);
DISPLAY 0.638298 (-5046 3450);
PAINT MONO (-5046 3450);
FORCEPROP 2 LAST CDS_LIB standard
J 0
(-4825 3450);
PAINT MONO (-4825 3450);
DISPLAY INVISIBLE (-4825 3450);
FORCEPROP 1 LAST OFFPAGE TRUE
J 0
(-4500 3325);
DISPLAY 0.872340 (-4500 3325);
DISPLAY INVISIBLE (-4500 3325);
FORCEPROP 1 LAST COMMENT_BODY TRUE
J 0
(-4700 3350);
DISPLAY 0.872340 (-4700 3350);
PAINT GREEN (-4700 3350);
DISPLAY INVISIBLE (-4700 3350);
FORCEPROP 2 LAST PATH I20
J 0
(-4775 3525);
DISPLAY 1.021277 (-4775 3525);
DISPLAY INVISIBLE (-4775 3525);
FORCEADD OFFPAGE..1
(-4825 4075);
FORCEPROP 2 LAST $XR1 112 
J 0
(-5166 4075);
DISPLAY 0.638298 (-5166 4075);
PAINT MONO (-5166 4075);
FORCEPROP 2 LAST $XR0 58 
J 0
(-5046 4075);
DISPLAY 0.638298 (-5046 4075);
PAINT MONO (-5046 4075);
FORCEPROP 2 LAST CDS_LIB standard
J 0
(-4825 4075);
PAINT MONO (-4825 4075);
DISPLAY INVISIBLE (-4825 4075);
FORCEPROP 1 LAST OFFPAGE TRUE
J 0
(-4500 3950);
DISPLAY 0.872340 (-4500 3950);
DISPLAY INVISIBLE (-4500 3950);
FORCEPROP 1 LAST COMMENT_BODY TRUE
J 0
(-4700 3975);
DISPLAY 0.872340 (-4700 3975);
PAINT GREEN (-4700 3975);
DISPLAY INVISIBLE (-4700 3975);
FORCEPROP 2 LAST PATH I21
J 0
(-4775 4150);
DISPLAY 1.021277 (-4775 4150);
DISPLAY INVISIBLE (-4775 4150);
FORCEADD TAP..1
R 2
(-3900 2400);
FORCEPROP 3 LASTPIN (-3850 2400) SIG_NAME M_H_CPU1_SB_CB<3>
J 0
(-3840 2410);
DISPLAY 0.659574 (-3840 2410);
PAINT MONO (-3840 2410);
DISPLAY INVISIBLE (-3840 2410);
FORCEPROP 1 LASTPIN (-3850 2400) BN 3
J 2
(-3838 2408);
DISPLAY 0.680851 (-3838 2408);
PAINT GREEN (-3838 2408);
FORCEPROP 2 LAST CDS_LIB standard
J 0
(-3900 2400);
DISPLAY INVISIBLE (-3900 2400);
FORCEPROP 1 LAST BODY_TYPE PLUMBING
J 2
(-3900 2450);
DISPLAY 0.872340 (-3900 2450);
PAINT GREEN (-3900 2450);
DISPLAY INVISIBLE (-3900 2450);
FORCEPROP 1 LAST HDL_TAP TRUE
J 2
(-4225 2275);
DISPLAY 0.872340 (-4225 2275);
DISPLAY INVISIBLE (-4225 2275);
FORCEPROP 1 LAST PATH I22
J 2
(-3898 2400);
DISPLAY 0.872340 (-3898 2400);
PAINT GREEN (-3898 2400);
DISPLAY INVISIBLE (-3898 2400);
FORCEADD TAP..1
R 2
(-3900 2300);
FORCEPROP 3 LASTPIN (-3850 2300) SIG_NAME M_H_CPU1_SB_CB<1>
J 0
(-3840 2310);
DISPLAY 0.659574 (-3840 2310);
PAINT MONO (-3840 2310);
DISPLAY INVISIBLE (-3840 2310);
FORCEPROP 1 LASTPIN (-3850 2300) BN 1
J 2
(-3838 2308);
DISPLAY 0.680851 (-3838 2308);
PAINT GREEN (-3838 2308);
FORCEPROP 2 LAST CDS_LIB standard
J 0
(-3900 2300);
DISPLAY INVISIBLE (-3900 2300);
FORCEPROP 1 LAST BODY_TYPE PLUMBING
J 2
(-3900 2350);
DISPLAY 0.872340 (-3900 2350);
PAINT GREEN (-3900 2350);
DISPLAY INVISIBLE (-3900 2350);
FORCEPROP 1 LAST HDL_TAP TRUE
J 2
(-4225 2175);
DISPLAY 0.872340 (-4225 2175);
DISPLAY INVISIBLE (-4225 2175);
FORCEPROP 1 LAST PATH I23
J 2
(-3898 2300);
DISPLAY 0.872340 (-3898 2300);
PAINT GREEN (-3898 2300);
DISPLAY INVISIBLE (-3898 2300);
FORCEADD TAP..1
R 2
(-3900 2350);
FORCEPROP 3 LASTPIN (-3850 2350) SIG_NAME M_H_CPU1_SB_CB<2>
J 0
(-3840 2360);
DISPLAY 0.659574 (-3840 2360);
PAINT MONO (-3840 2360);
DISPLAY INVISIBLE (-3840 2360);
FORCEPROP 1 LASTPIN (-3850 2350) BN 2
J 2
(-3838 2358);
DISPLAY 0.680851 (-3838 2358);
PAINT GREEN (-3838 2358);
FORCEPROP 2 LAST CDS_LIB standard
J 0
(-3900 2350);
DISPLAY INVISIBLE (-3900 2350);
FORCEPROP 1 LAST BODY_TYPE PLUMBING
J 2
(-3900 2400);
DISPLAY 0.872340 (-3900 2400);
PAINT GREEN (-3900 2400);
DISPLAY INVISIBLE (-3900 2400);
FORCEPROP 1 LAST HDL_TAP TRUE
J 2
(-4225 2225);
DISPLAY 0.872340 (-4225 2225);
DISPLAY INVISIBLE (-4225 2225);
FORCEPROP 1 LAST PATH I24
J 2
(-3898 2350);
DISPLAY 0.872340 (-3898 2350);
PAINT GREEN (-3898 2350);
DISPLAY INVISIBLE (-3898 2350);
FORCEADD TAP..1
R 2
(-3900 2550);
FORCEPROP 3 LASTPIN (-3850 2550) SIG_NAME M_H_CPU1_SB_CB<6>
J 0
(-3840 2560);
DISPLAY 0.659574 (-3840 2560);
PAINT MONO (-3840 2560);
DISPLAY INVISIBLE (-3840 2560);
FORCEPROP 1 LASTPIN (-3850 2550) BN 6
J 2
(-3838 2558);
DISPLAY 0.680851 (-3838 2558);
PAINT GREEN (-3838 2558);
FORCEPROP 2 LAST CDS_LIB standard
J 0
(-3900 2550);
DISPLAY INVISIBLE (-3900 2550);
FORCEPROP 1 LAST BODY_TYPE PLUMBING
J 2
(-3900 2600);
DISPLAY 0.872340 (-3900 2600);
PAINT GREEN (-3900 2600);
DISPLAY INVISIBLE (-3900 2600);
FORCEPROP 1 LAST HDL_TAP TRUE
J 2
(-4225 2425);
DISPLAY 0.872340 (-4225 2425);
DISPLAY INVISIBLE (-4225 2425);
FORCEPROP 1 LAST PATH I25
J 2
(-3898 2550);
DISPLAY 0.872340 (-3898 2550);
PAINT GREEN (-3898 2550);
DISPLAY INVISIBLE (-3898 2550);
FORCEADD TAP..1
R 2
(-3900 2800);
FORCEPROP 3 LASTPIN (-3850 2800) SIG_NAME M_H_CPU1_SA_CB<2>
J 0
(-3840 2810);
DISPLAY 0.659574 (-3840 2810);
PAINT MONO (-3840 2810);
DISPLAY INVISIBLE (-3840 2810);
FORCEPROP 1 LASTPIN (-3850 2800) BN 2
J 2
(-3838 2808);
DISPLAY 0.680851 (-3838 2808);
PAINT GREEN (-3838 2808);
FORCEPROP 2 LAST CDS_LIB standard
J 0
(-3900 2800);
DISPLAY INVISIBLE (-3900 2800);
FORCEPROP 1 LAST BODY_TYPE PLUMBING
J 2
(-3900 2850);
DISPLAY 0.872340 (-3900 2850);
PAINT GREEN (-3900 2850);
DISPLAY INVISIBLE (-3900 2850);
FORCEPROP 1 LAST HDL_TAP TRUE
J 2
(-4225 2675);
DISPLAY 0.872340 (-4225 2675);
DISPLAY INVISIBLE (-4225 2675);
FORCEPROP 1 LAST PATH I26
J 2
(-3898 2800);
DISPLAY 0.872340 (-3898 2800);
PAINT GREEN (-3898 2800);
DISPLAY INVISIBLE (-3898 2800);
FORCEADD TAP..1
R 2
(-3900 2750);
FORCEPROP 3 LASTPIN (-3850 2750) SIG_NAME M_H_CPU1_SA_CB<1>
J 0
(-3840 2760);
DISPLAY 0.659574 (-3840 2760);
PAINT MONO (-3840 2760);
DISPLAY INVISIBLE (-3840 2760);
FORCEPROP 1 LASTPIN (-3850 2750) BN 1
J 2
(-3838 2758);
DISPLAY 0.680851 (-3838 2758);
PAINT GREEN (-3838 2758);
FORCEPROP 2 LAST CDS_LIB standard
J 0
(-3900 2750);
DISPLAY INVISIBLE (-3900 2750);
FORCEPROP 1 LAST BODY_TYPE PLUMBING
J 2
(-3900 2800);
DISPLAY 0.872340 (-3900 2800);
PAINT GREEN (-3900 2800);
DISPLAY INVISIBLE (-3900 2800);
FORCEPROP 1 LAST HDL_TAP TRUE
J 2
(-4225 2625);
DISPLAY 0.872340 (-4225 2625);
DISPLAY INVISIBLE (-4225 2625);
FORCEPROP 1 LAST PATH I27
J 2
(-3898 2750);
DISPLAY 0.872340 (-3898 2750);
PAINT GREEN (-3898 2750);
DISPLAY INVISIBLE (-3898 2750);
FORCEADD TAP..1
R 2
(-3900 2700);
FORCEPROP 3 LASTPIN (-3850 2700) SIG_NAME M_H_CPU1_SA_CB<0>
J 0
(-3840 2710);
DISPLAY 0.659574 (-3840 2710);
PAINT MONO (-3840 2710);
DISPLAY INVISIBLE (-3840 2710);
FORCEPROP 1 LASTPIN (-3850 2700) BN 0
J 2
(-3838 2708);
DISPLAY 0.680851 (-3838 2708);
PAINT GREEN (-3838 2708);
FORCEPROP 2 LAST CDS_LIB standard
J 0
(-3900 2700);
PAINT MONO (-3900 2700);
DISPLAY INVISIBLE (-3900 2700);
FORCEPROP 1 LAST BODY_TYPE PLUMBING
J 2
(-3900 2750);
DISPLAY 0.872340 (-3900 2750);
PAINT GREEN (-3900 2750);
DISPLAY INVISIBLE (-3900 2750);
FORCEPROP 1 LAST HDL_TAP TRUE
J 2
(-4225 2575);
DISPLAY 0.872340 (-4225 2575);
DISPLAY INVISIBLE (-4225 2575);
FORCEPROP 1 LAST PATH I28
J 2
(-3898 2700);
DISPLAY 0.872340 (-3898 2700);
PAINT GREEN (-3898 2700);
DISPLAY INVISIBLE (-3898 2700);
FORCEADD TAP..1
R 2
(-3900 2600);
FORCEPROP 3 LASTPIN (-3850 2600) SIG_NAME M_H_CPU1_SB_CB<7>
J 0
(-3840 2610);
DISPLAY 0.659574 (-3840 2610);
PAINT MONO (-3840 2610);
DISPLAY INVISIBLE (-3840 2610);
FORCEPROP 1 LASTPIN (-3850 2600) BN 7
J 2
(-3838 2608);
DISPLAY 0.680851 (-3838 2608);
PAINT GREEN (-3838 2608);
FORCEPROP 2 LAST CDS_LIB standard
J 0
(-3900 2600);
DISPLAY INVISIBLE (-3900 2600);
FORCEPROP 1 LAST BODY_TYPE PLUMBING
J 2
(-3900 2650);
DISPLAY 0.872340 (-3900 2650);
PAINT GREEN (-3900 2650);
DISPLAY INVISIBLE (-3900 2650);
FORCEPROP 1 LAST HDL_TAP TRUE
J 2
(-4225 2475);
DISPLAY 0.872340 (-4225 2475);
DISPLAY INVISIBLE (-4225 2475);
FORCEPROP 1 LAST PATH I29
J 2
(-3898 2600);
DISPLAY 0.872340 (-3898 2600);
PAINT GREEN (-3898 2600);
DISPLAY INVISIBLE (-3898 2600);
FORCEADD OFFPAGE..3
R 2
(-4825 1600);
FORCEPROP 2 LAST $XR0 114 
J 0
(-5105 1600);
DISPLAY 0.638298 (-5105 1600);
PAINT MONO (-5105 1600);
FORCEPROP 2 LAST CDS_LIB standard
J 0
(-4825 1600);
PAINT MONO (-4825 1600);
DISPLAY INVISIBLE (-4825 1600);
FORCEPROP 1 LAST OFFPAGE TRUE
J 2
(-5150 1475);
DISPLAY 0.872340 (-5150 1475);
DISPLAY INVISIBLE (-5150 1475);
FORCEPROP 1 LAST COMMENT_BODY TRUE
J 2
(-4775 1500);
DISPLAY 0.872340 (-4775 1500);
PAINT GREEN (-4775 1500);
DISPLAY INVISIBLE (-4775 1500);
FORCEPROP 2 LAST PATH I3
J 0
(-4775 1675);
DISPLAY 1.021277 (-4775 1675);
DISPLAY INVISIBLE (-4775 1675);
FORCEADD TAP..1
R 2
(-3900 2900);
FORCEPROP 3 LASTPIN (-3850 2900) SIG_NAME M_H_CPU1_SA_CB<4>
J 0
(-3840 2910);
DISPLAY 0.659574 (-3840 2910);
PAINT MONO (-3840 2910);
DISPLAY INVISIBLE (-3840 2910);
FORCEPROP 1 LASTPIN (-3850 2900) BN 4
J 2
(-3838 2908);
DISPLAY 0.680851 (-3838 2908);
PAINT GREEN (-3838 2908);
FORCEPROP 2 LAST CDS_LIB standard
J 0
(-3900 2900);
DISPLAY INVISIBLE (-3900 2900);
FORCEPROP 1 LAST BODY_TYPE PLUMBING
J 2
(-3900 2950);
DISPLAY 0.872340 (-3900 2950);
PAINT GREEN (-3900 2950);
DISPLAY INVISIBLE (-3900 2950);
FORCEPROP 1 LAST HDL_TAP TRUE
J 2
(-4225 2775);
DISPLAY 0.872340 (-4225 2775);
DISPLAY INVISIBLE (-4225 2775);
FORCEPROP 1 LAST PATH I30
J 2
(-3898 2900);
DISPLAY 0.872340 (-3898 2900);
PAINT GREEN (-3898 2900);
DISPLAY INVISIBLE (-3898 2900);
FORCEADD TAP..1
R 2
(-3900 2850);
FORCEPROP 3 LASTPIN (-3850 2850) SIG_NAME M_H_CPU1_SA_CB<3>
J 0
(-3840 2860);
DISPLAY 0.659574 (-3840 2860);
PAINT MONO (-3840 2860);
DISPLAY INVISIBLE (-3840 2860);
FORCEPROP 1 LASTPIN (-3850 2850) BN 3
J 2
(-3838 2858);
DISPLAY 0.680851 (-3838 2858);
PAINT GREEN (-3838 2858);
FORCEPROP 2 LAST CDS_LIB standard
J 0
(-3900 2850);
DISPLAY INVISIBLE (-3900 2850);
FORCEPROP 1 LAST BODY_TYPE PLUMBING
J 2
(-3900 2900);
DISPLAY 0.872340 (-3900 2900);
PAINT GREEN (-3900 2900);
DISPLAY INVISIBLE (-3900 2900);
FORCEPROP 1 LAST HDL_TAP TRUE
J 2
(-4225 2725);
DISPLAY 0.872340 (-4225 2725);
DISPLAY INVISIBLE (-4225 2725);
FORCEPROP 1 LAST PATH I31
J 2
(-3898 2850);
DISPLAY 0.872340 (-3898 2850);
PAINT GREEN (-3898 2850);
DISPLAY INVISIBLE (-3898 2850);
FORCEADD TAP..1
R 2
(-3900 3000);
FORCEPROP 3 LASTPIN (-3850 3000) SIG_NAME M_H_CPU1_SA_CB<6>
J 0
(-3840 3010);
DISPLAY 0.659574 (-3840 3010);
PAINT MONO (-3840 3010);
DISPLAY INVISIBLE (-3840 3010);
FORCEPROP 1 LASTPIN (-3850 3000) BN 6
J 2
(-3838 3008);
DISPLAY 0.680851 (-3838 3008);
PAINT GREEN (-3838 3008);
FORCEPROP 2 LAST CDS_LIB standard
J 0
(-3900 3000);
DISPLAY INVISIBLE (-3900 3000);
FORCEPROP 1 LAST BODY_TYPE PLUMBING
J 2
(-3900 3050);
DISPLAY 0.872340 (-3900 3050);
PAINT GREEN (-3900 3050);
DISPLAY INVISIBLE (-3900 3050);
FORCEPROP 1 LAST HDL_TAP TRUE
J 2
(-4225 2875);
DISPLAY 0.872340 (-4225 2875);
DISPLAY INVISIBLE (-4225 2875);
FORCEPROP 1 LAST PATH I32
J 2
(-3898 3000);
DISPLAY 0.872340 (-3898 3000);
PAINT GREEN (-3898 3000);
DISPLAY INVISIBLE (-3898 3000);
FORCEADD TAP..1
R 2
(-3900 3050);
FORCEPROP 3 LASTPIN (-3850 3050) SIG_NAME M_H_CPU1_SA_CB<7>
J 0
(-3840 3060);
DISPLAY 0.659574 (-3840 3060);
PAINT MONO (-3840 3060);
DISPLAY INVISIBLE (-3840 3060);
FORCEPROP 1 LASTPIN (-3850 3050) BN 7
J 2
(-3838 3058);
DISPLAY 0.680851 (-3838 3058);
PAINT GREEN (-3838 3058);
FORCEPROP 2 LAST CDS_LIB standard
J 0
(-3900 3050);
DISPLAY INVISIBLE (-3900 3050);
FORCEPROP 1 LAST BODY_TYPE PLUMBING
J 2
(-3900 3100);
DISPLAY 0.872340 (-3900 3100);
PAINT GREEN (-3900 3100);
DISPLAY INVISIBLE (-3900 3100);
FORCEPROP 1 LAST HDL_TAP TRUE
J 2
(-4225 2925);
DISPLAY 0.872340 (-4225 2925);
DISPLAY INVISIBLE (-4225 2925);
FORCEPROP 1 LAST PATH I33
J 2
(-3898 3050);
DISPLAY 0.872340 (-3898 3050);
PAINT GREEN (-3898 3050);
DISPLAY INVISIBLE (-3898 3050);
FORCEADD TAP..1
R 2
(-3900 2950);
FORCEPROP 3 LASTPIN (-3850 2950) SIG_NAME M_H_CPU1_SA_CB<5>
J 0
(-3840 2960);
DISPLAY 0.659574 (-3840 2960);
PAINT MONO (-3840 2960);
DISPLAY INVISIBLE (-3840 2960);
FORCEPROP 1 LASTPIN (-3850 2950) BN 5
J 2
(-3838 2958);
DISPLAY 0.680851 (-3838 2958);
PAINT GREEN (-3838 2958);
FORCEPROP 2 LAST CDS_LIB standard
J 0
(-3900 2950);
DISPLAY INVISIBLE (-3900 2950);
FORCEPROP 1 LAST BODY_TYPE PLUMBING
J 2
(-3900 3000);
DISPLAY 0.872340 (-3900 3000);
PAINT GREEN (-3900 3000);
DISPLAY INVISIBLE (-3900 3000);
FORCEPROP 1 LAST HDL_TAP TRUE
J 2
(-4225 2825);
DISPLAY 0.872340 (-4225 2825);
DISPLAY INVISIBLE (-4225 2825);
FORCEPROP 1 LAST PATH I34
J 2
(-3898 2950);
DISPLAY 0.872340 (-3898 2950);
PAINT GREEN (-3898 2950);
DISPLAY INVISIBLE (-3898 2950);
FORCEADD TAP..1
R 2
(-3900 3750);
FORCEPROP 3 LASTPIN (-3850 3750) SIG_NAME M_H_CPU1_SB_CA<0>
J 0
(-3840 3760);
DISPLAY 0.659574 (-3840 3760);
PAINT MONO (-3840 3760);
DISPLAY INVISIBLE (-3840 3760);
FORCEPROP 1 LASTPIN (-3850 3750) BN 0
J 2
(-3838 3758);
DISPLAY 0.680851 (-3838 3758);
PAINT GREEN (-3838 3758);
FORCEPROP 2 LAST CDS_LIB standard
J 0
(-3900 3750);
DISPLAY INVISIBLE (-3900 3750);
FORCEPROP 1 LAST BODY_TYPE PLUMBING
J 2
(-3900 3800);
DISPLAY 0.872340 (-3900 3800);
PAINT GREEN (-3900 3800);
DISPLAY INVISIBLE (-3900 3800);
FORCEPROP 1 LAST HDL_TAP TRUE
J 2
(-4225 3625);
DISPLAY 0.872340 (-4225 3625);
DISPLAY INVISIBLE (-4225 3625);
FORCEPROP 1 LAST PATH I35
J 2
(-3898 3750);
DISPLAY 0.872340 (-3898 3750);
PAINT GREEN (-3898 3750);
DISPLAY INVISIBLE (-3898 3750);
FORCEADD TAP..1
R 2
(-3900 3800);
FORCEPROP 3 LASTPIN (-3850 3800) SIG_NAME M_H_CPU1_SB_CA<1>
J 0
(-3840 3810);
DISPLAY 0.659574 (-3840 3810);
PAINT MONO (-3840 3810);
DISPLAY INVISIBLE (-3840 3810);
FORCEPROP 1 LASTPIN (-3850 3800) BN 1
J 2
(-3838 3808);
DISPLAY 0.680851 (-3838 3808);
PAINT GREEN (-3838 3808);
FORCEPROP 2 LAST CDS_LIB standard
J 0
(-3900 3800);
DISPLAY INVISIBLE (-3900 3800);
FORCEPROP 1 LAST BODY_TYPE PLUMBING
J 2
(-3900 3850);
DISPLAY 0.872340 (-3900 3850);
PAINT GREEN (-3900 3850);
DISPLAY INVISIBLE (-3900 3850);
FORCEPROP 1 LAST HDL_TAP TRUE
J 2
(-4225 3675);
DISPLAY 0.872340 (-4225 3675);
DISPLAY INVISIBLE (-4225 3675);
FORCEPROP 1 LAST PATH I36
J 2
(-3898 3800);
DISPLAY 0.872340 (-3898 3800);
PAINT GREEN (-3898 3800);
DISPLAY INVISIBLE (-3898 3800);
FORCEADD TAP..1
R 2
(-3900 3850);
FORCEPROP 3 LASTPIN (-3850 3850) SIG_NAME M_H_CPU1_SB_CA<2>
J 0
(-3840 3860);
DISPLAY 0.659574 (-3840 3860);
PAINT MONO (-3840 3860);
DISPLAY INVISIBLE (-3840 3860);
FORCEPROP 1 LASTPIN (-3850 3850) BN 2
J 2
(-3838 3858);
DISPLAY 0.680851 (-3838 3858);
PAINT GREEN (-3838 3858);
FORCEPROP 2 LAST CDS_LIB standard
J 0
(-3900 3850);
DISPLAY INVISIBLE (-3900 3850);
FORCEPROP 1 LAST BODY_TYPE PLUMBING
J 2
(-3900 3900);
DISPLAY 0.872340 (-3900 3900);
PAINT GREEN (-3900 3900);
DISPLAY INVISIBLE (-3900 3900);
FORCEPROP 1 LAST HDL_TAP TRUE
J 2
(-4225 3725);
DISPLAY 0.872340 (-4225 3725);
DISPLAY INVISIBLE (-4225 3725);
FORCEPROP 1 LAST PATH I37
J 2
(-3898 3850);
DISPLAY 0.872340 (-3898 3850);
PAINT GREEN (-3898 3850);
DISPLAY INVISIBLE (-3898 3850);
FORCEADD TAP..1
R 2
(-3900 3950);
FORCEPROP 3 LASTPIN (-3850 3950) SIG_NAME M_H_CPU1_SB_CA<4>
J 0
(-3840 3960);
DISPLAY 0.659574 (-3840 3960);
PAINT MONO (-3840 3960);
DISPLAY INVISIBLE (-3840 3960);
FORCEPROP 1 LASTPIN (-3850 3950) BN 4
J 2
(-3838 3958);
DISPLAY 0.680851 (-3838 3958);
PAINT GREEN (-3838 3958);
FORCEPROP 2 LAST CDS_LIB standard
J 0
(-3900 3950);
DISPLAY INVISIBLE (-3900 3950);
FORCEPROP 1 LAST BODY_TYPE PLUMBING
J 2
(-3900 4000);
DISPLAY 0.872340 (-3900 4000);
PAINT GREEN (-3900 4000);
DISPLAY INVISIBLE (-3900 4000);
FORCEPROP 1 LAST HDL_TAP TRUE
J 2
(-4225 3825);
DISPLAY 0.872340 (-4225 3825);
DISPLAY INVISIBLE (-4225 3825);
FORCEPROP 1 LAST PATH I38
J 2
(-3898 3950);
DISPLAY 0.872340 (-3898 3950);
PAINT GREEN (-3898 3950);
DISPLAY INVISIBLE (-3898 3950);
FORCEADD TAP..1
R 2
(-3900 3900);
FORCEPROP 3 LASTPIN (-3850 3900) SIG_NAME M_H_CPU1_SB_CA<3>
J 0
(-3840 3910);
DISPLAY 0.659574 (-3840 3910);
PAINT MONO (-3840 3910);
DISPLAY INVISIBLE (-3840 3910);
FORCEPROP 1 LASTPIN (-3850 3900) BN 3
J 2
(-3838 3908);
DISPLAY 0.680851 (-3838 3908);
PAINT GREEN (-3838 3908);
FORCEPROP 2 LAST CDS_LIB standard
J 0
(-3900 3900);
DISPLAY INVISIBLE (-3900 3900);
FORCEPROP 1 LAST BODY_TYPE PLUMBING
J 2
(-3900 3950);
DISPLAY 0.872340 (-3900 3950);
PAINT GREEN (-3900 3950);
DISPLAY INVISIBLE (-3900 3950);
FORCEPROP 1 LAST HDL_TAP TRUE
J 2
(-4225 3775);
DISPLAY 0.872340 (-4225 3775);
DISPLAY INVISIBLE (-4225 3775);
FORCEPROP 1 LAST PATH I39
J 2
(-3898 3900);
DISPLAY 0.872340 (-3898 3900);
PAINT GREEN (-3898 3900);
DISPLAY INVISIBLE (-3898 3900);
FORCEADD TAP..1
R 2
(-3900 4050);
FORCEPROP 3 LASTPIN (-3850 4050) SIG_NAME M_H_CPU1_SB_CA<6>
J 0
(-3840 4060);
DISPLAY 0.659574 (-3840 4060);
PAINT MONO (-3840 4060);
DISPLAY INVISIBLE (-3840 4060);
FORCEPROP 1 LASTPIN (-3850 4050) BN 6
J 2
(-3838 4058);
DISPLAY 0.680851 (-3838 4058);
PAINT GREEN (-3838 4058);
FORCEPROP 2 LAST CDS_LIB standard
J 0
(-3900 4050);
DISPLAY INVISIBLE (-3900 4050);
FORCEPROP 1 LAST BODY_TYPE PLUMBING
J 2
(-3900 4100);
DISPLAY 0.872340 (-3900 4100);
PAINT GREEN (-3900 4100);
DISPLAY INVISIBLE (-3900 4100);
FORCEPROP 1 LAST HDL_TAP TRUE
J 2
(-4225 3925);
DISPLAY 0.872340 (-4225 3925);
DISPLAY INVISIBLE (-4225 3925);
FORCEPROP 1 LAST PATH I40
J 2
(-3898 4050);
DISPLAY 0.872340 (-3898 4050);
PAINT GREEN (-3898 4050);
DISPLAY INVISIBLE (-3898 4050);
FORCEADD TAP..1
R 2
(-3900 4000);
FORCEPROP 3 LASTPIN (-3850 4000) SIG_NAME M_H_CPU1_SB_CA<5>
J 0
(-3840 4010);
DISPLAY 0.659574 (-3840 4010);
PAINT MONO (-3840 4010);
DISPLAY INVISIBLE (-3840 4010);
FORCEPROP 1 LASTPIN (-3850 4000) BN 5
J 2
(-3838 4008);
DISPLAY 0.680851 (-3838 4008);
PAINT GREEN (-3838 4008);
FORCEPROP 2 LAST CDS_LIB standard
J 0
(-3900 4000);
DISPLAY INVISIBLE (-3900 4000);
FORCEPROP 1 LAST BODY_TYPE PLUMBING
J 2
(-3900 4050);
DISPLAY 0.872340 (-3900 4050);
PAINT GREEN (-3900 4050);
DISPLAY INVISIBLE (-3900 4050);
FORCEPROP 1 LAST HDL_TAP TRUE
J 2
(-4225 3875);
DISPLAY 0.872340 (-4225 3875);
DISPLAY INVISIBLE (-4225 3875);
FORCEPROP 1 LAST PATH I41
J 2
(-3898 4000);
DISPLAY 0.872340 (-3898 4000);
PAINT GREEN (-3898 4000);
DISPLAY INVISIBLE (-3898 4000);
FORCEADD TAP..1
R 2
(-3900 4300);
FORCEPROP 3 LASTPIN (-3850 4300) SIG_NAME M_H_CPU1_SA_CA<3>
J 0
(-3840 4310);
DISPLAY 0.659574 (-3840 4310);
PAINT MONO (-3840 4310);
DISPLAY INVISIBLE (-3840 4310);
FORCEPROP 1 LASTPIN (-3850 4300) BN 3
J 2
(-3838 4308);
DISPLAY 0.680851 (-3838 4308);
PAINT GREEN (-3838 4308);
FORCEPROP 2 LAST CDS_LIB standard
J 0
(-3900 4300);
DISPLAY INVISIBLE (-3900 4300);
FORCEPROP 1 LAST BODY_TYPE PLUMBING
J 2
(-3900 4350);
DISPLAY 0.872340 (-3900 4350);
PAINT GREEN (-3900 4350);
DISPLAY INVISIBLE (-3900 4350);
FORCEPROP 1 LAST HDL_TAP TRUE
J 2
(-4225 4175);
DISPLAY 0.872340 (-4225 4175);
DISPLAY INVISIBLE (-4225 4175);
FORCEPROP 1 LAST PATH I42
J 2
(-3898 4300);
DISPLAY 0.872340 (-3898 4300);
PAINT GREEN (-3898 4300);
DISPLAY INVISIBLE (-3898 4300);
FORCEADD TAP..1
R 2
(-3900 4250);
FORCEPROP 3 LASTPIN (-3850 4250) SIG_NAME M_H_CPU1_SA_CA<2>
J 0
(-3840 4260);
DISPLAY 0.659574 (-3840 4260);
PAINT MONO (-3840 4260);
DISPLAY INVISIBLE (-3840 4260);
FORCEPROP 1 LASTPIN (-3850 4250) BN 2
J 2
(-3838 4258);
DISPLAY 0.680851 (-3838 4258);
PAINT GREEN (-3838 4258);
FORCEPROP 2 LAST CDS_LIB standard
J 0
(-3900 4250);
DISPLAY INVISIBLE (-3900 4250);
FORCEPROP 1 LAST BODY_TYPE PLUMBING
J 2
(-3900 4300);
DISPLAY 0.872340 (-3900 4300);
PAINT GREEN (-3900 4300);
DISPLAY INVISIBLE (-3900 4300);
FORCEPROP 1 LAST HDL_TAP TRUE
J 2
(-4225 4125);
DISPLAY 0.872340 (-4225 4125);
DISPLAY INVISIBLE (-4225 4125);
FORCEPROP 1 LAST PATH I43
J 2
(-3898 4250);
DISPLAY 0.872340 (-3898 4250);
PAINT GREEN (-3898 4250);
DISPLAY INVISIBLE (-3898 4250);
FORCEADD TAP..1
R 2
(-3900 4200);
FORCEPROP 3 LASTPIN (-3850 4200) SIG_NAME M_H_CPU1_SA_CA<1>
J 0
(-3840 4210);
DISPLAY 0.659574 (-3840 4210);
PAINT MONO (-3840 4210);
DISPLAY INVISIBLE (-3840 4210);
FORCEPROP 1 LASTPIN (-3850 4200) BN 1
J 2
(-3838 4208);
DISPLAY 0.680851 (-3838 4208);
PAINT GREEN (-3838 4208);
FORCEPROP 2 LAST CDS_LIB standard
J 0
(-3900 4200);
DISPLAY INVISIBLE (-3900 4200);
FORCEPROP 1 LAST BODY_TYPE PLUMBING
J 2
(-3900 4250);
DISPLAY 0.872340 (-3900 4250);
PAINT GREEN (-3900 4250);
DISPLAY INVISIBLE (-3900 4250);
FORCEPROP 1 LAST HDL_TAP TRUE
J 2
(-4225 4075);
DISPLAY 0.872340 (-4225 4075);
DISPLAY INVISIBLE (-4225 4075);
FORCEPROP 1 LAST PATH I44
J 2
(-3898 4200);
DISPLAY 0.872340 (-3898 4200);
PAINT GREEN (-3898 4200);
DISPLAY INVISIBLE (-3898 4200);
FORCEADD TAP..1
R 2
(-3900 4150);
FORCEPROP 3 LASTPIN (-3850 4150) SIG_NAME M_H_CPU1_SA_CA<0>
J 0
(-3840 4160);
DISPLAY 0.659574 (-3840 4160);
PAINT MONO (-3840 4160);
DISPLAY INVISIBLE (-3840 4160);
FORCEPROP 1 LASTPIN (-3850 4150) BN 0
J 2
(-3838 4158);
DISPLAY 0.680851 (-3838 4158);
PAINT GREEN (-3838 4158);
FORCEPROP 2 LAST CDS_LIB standard
J 0
(-3900 4150);
DISPLAY INVISIBLE (-3900 4150);
FORCEPROP 1 LAST BODY_TYPE PLUMBING
J 2
(-3900 4200);
DISPLAY 0.872340 (-3900 4200);
PAINT GREEN (-3900 4200);
DISPLAY INVISIBLE (-3900 4200);
FORCEPROP 1 LAST HDL_TAP TRUE
J 2
(-4225 4025);
DISPLAY 0.872340 (-4225 4025);
DISPLAY INVISIBLE (-4225 4025);
FORCEPROP 1 LAST PATH I45
J 2
(-3898 4150);
DISPLAY 0.872340 (-3898 4150);
PAINT GREEN (-3898 4150);
DISPLAY INVISIBLE (-3898 4150);
FORCEADD TAP..1
(-2250 1250);
FORCEPROP 3 LASTPIN (-2300 1250) SIG_NAME M_H_CPU1_SB_DQ<0>
J 0
(-2290 1260);
DISPLAY 0.659574 (-2290 1260);
PAINT MONO (-2290 1260);
DISPLAY INVISIBLE (-2290 1260);
FORCEPROP 1 LASTPIN (-2300 1250) BN 0
J 0
(-2312 1258);
DISPLAY 0.680851 (-2312 1258);
PAINT GREEN (-2312 1258);
FORCEPROP 2 LAST CDS_LIB standard
J 0
(-2250 1250);
PAINT MONO (-2250 1250);
DISPLAY INVISIBLE (-2250 1250);
FORCEPROP 1 LAST BODY_TYPE PLUMBING
J 0
(-2250 1300);
DISPLAY 0.872340 (-2250 1300);
PAINT GREEN (-2250 1300);
DISPLAY INVISIBLE (-2250 1300);
FORCEPROP 1 LAST HDL_TAP TRUE
J 0
(-1925 1125);
DISPLAY 0.872340 (-1925 1125);
DISPLAY INVISIBLE (-1925 1125);
FORCEPROP 1 LAST PATH I46
J 0
(-2252 1250);
DISPLAY 0.872340 (-2252 1250);
PAINT GREEN (-2252 1250);
DISPLAY INVISIBLE (-2252 1250);
FORCEADD TAP..1
(-2250 1300);
FORCEPROP 3 LASTPIN (-2300 1300) SIG_NAME M_H_CPU1_SB_DQ<1>
J 0
(-2290 1310);
DISPLAY 0.659574 (-2290 1310);
PAINT MONO (-2290 1310);
DISPLAY INVISIBLE (-2290 1310);
FORCEPROP 1 LASTPIN (-2300 1300) BN 1
J 0
(-2312 1308);
DISPLAY 0.680851 (-2312 1308);
PAINT GREEN (-2312 1308);
FORCEPROP 2 LAST CDS_LIB standard
J 0
(-2250 1300);
PAINT MONO (-2250 1300);
DISPLAY INVISIBLE (-2250 1300);
FORCEPROP 1 LAST BODY_TYPE PLUMBING
J 0
(-2250 1350);
DISPLAY 0.872340 (-2250 1350);
PAINT GREEN (-2250 1350);
DISPLAY INVISIBLE (-2250 1350);
FORCEPROP 1 LAST HDL_TAP TRUE
J 0
(-1925 1175);
DISPLAY 0.872340 (-1925 1175);
DISPLAY INVISIBLE (-1925 1175);
FORCEPROP 1 LAST PATH I47
J 0
(-2252 1300);
DISPLAY 0.872340 (-2252 1300);
PAINT GREEN (-2252 1300);
DISPLAY INVISIBLE (-2252 1300);
FORCEADD TAP..1
(-2250 1350);
FORCEPROP 3 LASTPIN (-2300 1350) SIG_NAME M_H_CPU1_SB_DQ<2>
J 0
(-2290 1360);
DISPLAY 0.659574 (-2290 1360);
PAINT MONO (-2290 1360);
DISPLAY INVISIBLE (-2290 1360);
FORCEPROP 1 LASTPIN (-2300 1350) BN 2
J 0
(-2312 1358);
DISPLAY 0.680851 (-2312 1358);
PAINT GREEN (-2312 1358);
FORCEPROP 2 LAST CDS_LIB standard
J 0
(-2250 1350);
PAINT MONO (-2250 1350);
DISPLAY INVISIBLE (-2250 1350);
FORCEPROP 1 LAST BODY_TYPE PLUMBING
J 0
(-2250 1400);
DISPLAY 0.872340 (-2250 1400);
PAINT GREEN (-2250 1400);
DISPLAY INVISIBLE (-2250 1400);
FORCEPROP 1 LAST HDL_TAP TRUE
J 0
(-1925 1225);
DISPLAY 0.872340 (-1925 1225);
DISPLAY INVISIBLE (-1925 1225);
FORCEPROP 1 LAST PATH I48
J 0
(-2252 1350);
DISPLAY 0.872340 (-2252 1350);
PAINT GREEN (-2252 1350);
DISPLAY INVISIBLE (-2252 1350);
FORCEADD TAP..1
(-2250 1400);
FORCEPROP 3 LASTPIN (-2300 1400) SIG_NAME M_H_CPU1_SB_DQ<3>
J 0
(-2290 1410);
DISPLAY 0.659574 (-2290 1410);
PAINT MONO (-2290 1410);
DISPLAY INVISIBLE (-2290 1410);
FORCEPROP 1 LASTPIN (-2300 1400) BN 3
J 0
(-2312 1408);
DISPLAY 0.680851 (-2312 1408);
PAINT GREEN (-2312 1408);
FORCEPROP 2 LAST CDS_LIB standard
J 0
(-2250 1400);
PAINT MONO (-2250 1400);
DISPLAY INVISIBLE (-2250 1400);
FORCEPROP 1 LAST BODY_TYPE PLUMBING
J 0
(-2250 1450);
DISPLAY 0.872340 (-2250 1450);
PAINT GREEN (-2250 1450);
DISPLAY INVISIBLE (-2250 1450);
FORCEPROP 1 LAST HDL_TAP TRUE
J 0
(-1925 1275);
DISPLAY 0.872340 (-1925 1275);
DISPLAY INVISIBLE (-1925 1275);
FORCEPROP 1 LAST PATH I49
J 0
(-2252 1400);
DISPLAY 0.872340 (-2252 1400);
PAINT GREEN (-2252 1400);
DISPLAY INVISIBLE (-2252 1400);
FORCEADD OFFPAGE..1
(-4725 1900);
FORCEPROP 2 LAST $XR7 112 
J 0
(-5217 1936);
DISPLAY 0.638298 (-5217 1936);
PAINT MONO (-5217 1936);
FORCEPROP 2 LAST $XR6 111 
J 0
(-5097 1936);
DISPLAY 0.638298 (-5097 1936);
PAINT MONO (-5097 1936);
FORCEPROP 2 LAST $XR5 110 
J 0
(-5217 1864);
DISPLAY 0.638298 (-5217 1864);
PAINT MONO (-5217 1864);
FORCEPROP 2 LAST $XR4 109 
J 0
(-5097 1864);
DISPLAY 0.638298 (-5097 1864);
PAINT MONO (-5097 1864);
FORCEPROP 2 LAST $XR3 108 
J 0
(-4977 1864);
DISPLAY 0.638298 (-4977 1864);
PAINT MONO (-4977 1864);
FORCEPROP 2 LAST $XR2 107 
J 0
(-5217 1900);
DISPLAY 0.638298 (-5217 1900);
PAINT MONO (-5217 1900);
FORCEPROP 2 LAST $XR1 106 
J 0
(-5097 1900);
DISPLAY 0.638298 (-5097 1900);
PAINT MONO (-5097 1900);
FORCEPROP 2 LAST $XR0 230 
J 0
(-4977 1900);
DISPLAY 0.638298 (-4977 1900);
PAINT MONO (-4977 1900);
FORCEPROP 2 LAST CDS_LIB standard
J 0
(-4725 1900);
PAINT MONO (-4725 1900);
DISPLAY INVISIBLE (-4725 1900);
FORCEPROP 1 LAST OFFPAGE TRUE
J 0
(-4400 1775);
DISPLAY 0.872340 (-4400 1775);
DISPLAY INVISIBLE (-4400 1775);
FORCEPROP 1 LAST COMMENT_BODY TRUE
J 0
(-4600 1800);
DISPLAY 0.872340 (-4600 1800);
PAINT GREEN (-4600 1800);
DISPLAY INVISIBLE (-4600 1800);
FORCEPROP 2 LAST PATH I5
J 0
(-4675 1975);
DISPLAY 1.021277 (-4675 1975);
DISPLAY INVISIBLE (-4675 1975);
FORCEADD TAP..1
(-2250 1550);
FORCEPROP 3 LASTPIN (-2300 1550) SIG_NAME M_H_CPU1_SB_DQ<6>
J 0
(-2290 1560);
DISPLAY 0.659574 (-2290 1560);
PAINT MONO (-2290 1560);
DISPLAY INVISIBLE (-2290 1560);
FORCEPROP 1 LASTPIN (-2300 1550) BN 6
J 0
(-2312 1558);
DISPLAY 0.680851 (-2312 1558);
PAINT GREEN (-2312 1558);
FORCEPROP 2 LAST CDS_LIB standard
J 0
(-2250 1550);
PAINT MONO (-2250 1550);
DISPLAY INVISIBLE (-2250 1550);
FORCEPROP 1 LAST BODY_TYPE PLUMBING
J 0
(-2250 1600);
DISPLAY 0.872340 (-2250 1600);
PAINT GREEN (-2250 1600);
DISPLAY INVISIBLE (-2250 1600);
FORCEPROP 1 LAST HDL_TAP TRUE
J 0
(-1925 1425);
DISPLAY 0.872340 (-1925 1425);
DISPLAY INVISIBLE (-1925 1425);
FORCEPROP 1 LAST PATH I50
J 0
(-2252 1550);
DISPLAY 0.872340 (-2252 1550);
PAINT GREEN (-2252 1550);
DISPLAY INVISIBLE (-2252 1550);
FORCEADD TAP..1
(-2250 1450);
FORCEPROP 3 LASTPIN (-2300 1450) SIG_NAME M_H_CPU1_SB_DQ<4>
J 0
(-2290 1460);
DISPLAY 0.659574 (-2290 1460);
PAINT MONO (-2290 1460);
DISPLAY INVISIBLE (-2290 1460);
FORCEPROP 1 LASTPIN (-2300 1450) BN 4
J 0
(-2312 1458);
DISPLAY 0.680851 (-2312 1458);
PAINT GREEN (-2312 1458);
FORCEPROP 2 LAST CDS_LIB standard
J 0
(-2250 1450);
PAINT MONO (-2250 1450);
DISPLAY INVISIBLE (-2250 1450);
FORCEPROP 1 LAST BODY_TYPE PLUMBING
J 0
(-2250 1500);
DISPLAY 0.872340 (-2250 1500);
PAINT GREEN (-2250 1500);
DISPLAY INVISIBLE (-2250 1500);
FORCEPROP 1 LAST HDL_TAP TRUE
J 0
(-1925 1325);
DISPLAY 0.872340 (-1925 1325);
DISPLAY INVISIBLE (-1925 1325);
FORCEPROP 1 LAST PATH I51
J 0
(-2252 1450);
DISPLAY 0.872340 (-2252 1450);
PAINT GREEN (-2252 1450);
DISPLAY INVISIBLE (-2252 1450);
FORCEADD TAP..1
(-2250 1500);
FORCEPROP 3 LASTPIN (-2300 1500) SIG_NAME M_H_CPU1_SB_DQ<5>
J 0
(-2290 1510);
DISPLAY 0.659574 (-2290 1510);
PAINT MONO (-2290 1510);
DISPLAY INVISIBLE (-2290 1510);
FORCEPROP 1 LASTPIN (-2300 1500) BN 5
J 0
(-2312 1508);
DISPLAY 0.680851 (-2312 1508);
PAINT GREEN (-2312 1508);
FORCEPROP 2 LAST CDS_LIB standard
J 0
(-2250 1500);
PAINT MONO (-2250 1500);
DISPLAY INVISIBLE (-2250 1500);
FORCEPROP 1 LAST BODY_TYPE PLUMBING
J 0
(-2250 1550);
DISPLAY 0.872340 (-2250 1550);
PAINT GREEN (-2250 1550);
DISPLAY INVISIBLE (-2250 1550);
FORCEPROP 1 LAST HDL_TAP TRUE
J 0
(-1925 1375);
DISPLAY 0.872340 (-1925 1375);
DISPLAY INVISIBLE (-1925 1375);
FORCEPROP 1 LAST PATH I52
J 0
(-2252 1500);
DISPLAY 0.872340 (-2252 1500);
PAINT GREEN (-2252 1500);
DISPLAY INVISIBLE (-2252 1500);
FORCEADD TAP..1
(-2250 1650);
FORCEPROP 3 LASTPIN (-2300 1650) SIG_NAME M_H_CPU1_SB_DQ<8>
J 0
(-2290 1660);
DISPLAY 0.659574 (-2290 1660);
PAINT MONO (-2290 1660);
DISPLAY INVISIBLE (-2290 1660);
FORCEPROP 1 LASTPIN (-2300 1650) BN 8
J 0
(-2312 1658);
DISPLAY 0.680851 (-2312 1658);
PAINT GREEN (-2312 1658);
FORCEPROP 2 LAST CDS_LIB standard
J 0
(-2250 1650);
PAINT MONO (-2250 1650);
DISPLAY INVISIBLE (-2250 1650);
FORCEPROP 1 LAST BODY_TYPE PLUMBING
J 0
(-2250 1700);
DISPLAY 0.872340 (-2250 1700);
PAINT GREEN (-2250 1700);
DISPLAY INVISIBLE (-2250 1700);
FORCEPROP 1 LAST HDL_TAP TRUE
J 0
(-1925 1525);
DISPLAY 0.872340 (-1925 1525);
DISPLAY INVISIBLE (-1925 1525);
FORCEPROP 1 LAST PATH I53
J 0
(-2252 1650);
DISPLAY 0.872340 (-2252 1650);
PAINT GREEN (-2252 1650);
DISPLAY INVISIBLE (-2252 1650);
FORCEADD TAP..1
(-2250 1750);
FORCEPROP 3 LASTPIN (-2300 1750) SIG_NAME M_H_CPU1_SB_DQ<10>
J 0
(-2290 1760);
DISPLAY 0.659574 (-2290 1760);
PAINT MONO (-2290 1760);
DISPLAY INVISIBLE (-2290 1760);
FORCEPROP 1 LASTPIN (-2300 1750) BN 10
J 0
(-2312 1758);
DISPLAY 0.680851 (-2312 1758);
PAINT GREEN (-2312 1758);
FORCEPROP 2 LAST CDS_LIB standard
J 0
(-2250 1750);
PAINT MONO (-2250 1750);
DISPLAY INVISIBLE (-2250 1750);
FORCEPROP 1 LAST BODY_TYPE PLUMBING
J 0
(-2250 1800);
DISPLAY 0.872340 (-2250 1800);
PAINT GREEN (-2250 1800);
DISPLAY INVISIBLE (-2250 1800);
FORCEPROP 1 LAST HDL_TAP TRUE
J 0
(-1925 1625);
DISPLAY 0.872340 (-1925 1625);
DISPLAY INVISIBLE (-1925 1625);
FORCEPROP 1 LAST PATH I54
J 0
(-2252 1750);
DISPLAY 0.872340 (-2252 1750);
PAINT GREEN (-2252 1750);
DISPLAY INVISIBLE (-2252 1750);
FORCEADD TAP..1
(-2250 1800);
FORCEPROP 3 LASTPIN (-2300 1800) SIG_NAME M_H_CPU1_SB_DQ<11>
J 0
(-2290 1810);
DISPLAY 0.659574 (-2290 1810);
PAINT MONO (-2290 1810);
DISPLAY INVISIBLE (-2290 1810);
FORCEPROP 1 LASTPIN (-2300 1800) BN 11
J 0
(-2312 1808);
DISPLAY 0.680851 (-2312 1808);
PAINT GREEN (-2312 1808);
FORCEPROP 2 LAST CDS_LIB standard
J 0
(-2250 1800);
PAINT MONO (-2250 1800);
DISPLAY INVISIBLE (-2250 1800);
FORCEPROP 1 LAST BODY_TYPE PLUMBING
J 0
(-2250 1850);
DISPLAY 0.872340 (-2250 1850);
PAINT GREEN (-2250 1850);
DISPLAY INVISIBLE (-2250 1850);
FORCEPROP 1 LAST HDL_TAP TRUE
J 0
(-1925 1675);
DISPLAY 0.872340 (-1925 1675);
DISPLAY INVISIBLE (-1925 1675);
FORCEPROP 1 LAST PATH I55
J 0
(-2252 1800);
DISPLAY 0.872340 (-2252 1800);
PAINT GREEN (-2252 1800);
DISPLAY INVISIBLE (-2252 1800);
FORCEADD TAP..1
(-2250 1700);
FORCEPROP 3 LASTPIN (-2300 1700) SIG_NAME M_H_CPU1_SB_DQ<9>
J 0
(-2290 1710);
DISPLAY 0.659574 (-2290 1710);
PAINT MONO (-2290 1710);
DISPLAY INVISIBLE (-2290 1710);
FORCEPROP 1 LASTPIN (-2300 1700) BN 9
J 0
(-2312 1708);
DISPLAY 0.680851 (-2312 1708);
PAINT GREEN (-2312 1708);
FORCEPROP 2 LAST CDS_LIB standard
J 0
(-2250 1700);
PAINT MONO (-2250 1700);
DISPLAY INVISIBLE (-2250 1700);
FORCEPROP 1 LAST BODY_TYPE PLUMBING
J 0
(-2250 1750);
DISPLAY 0.872340 (-2250 1750);
PAINT GREEN (-2250 1750);
DISPLAY INVISIBLE (-2250 1750);
FORCEPROP 1 LAST HDL_TAP TRUE
J 0
(-1925 1575);
DISPLAY 0.872340 (-1925 1575);
DISPLAY INVISIBLE (-1925 1575);
FORCEPROP 1 LAST PATH I56
J 0
(-2252 1700);
DISPLAY 0.872340 (-2252 1700);
PAINT GREEN (-2252 1700);
DISPLAY INVISIBLE (-2252 1700);
FORCEADD TAP..1
(-2250 1600);
FORCEPROP 3 LASTPIN (-2300 1600) SIG_NAME M_H_CPU1_SB_DQ<7>
J 0
(-2290 1610);
DISPLAY 0.659574 (-2290 1610);
PAINT MONO (-2290 1610);
DISPLAY INVISIBLE (-2290 1610);
FORCEPROP 1 LASTPIN (-2300 1600) BN 7
J 0
(-2312 1608);
DISPLAY 0.680851 (-2312 1608);
PAINT GREEN (-2312 1608);
FORCEPROP 2 LAST CDS_LIB standard
J 0
(-2250 1600);
PAINT MONO (-2250 1600);
DISPLAY INVISIBLE (-2250 1600);
FORCEPROP 1 LAST BODY_TYPE PLUMBING
J 0
(-2250 1650);
DISPLAY 0.872340 (-2250 1650);
PAINT GREEN (-2250 1650);
DISPLAY INVISIBLE (-2250 1650);
FORCEPROP 1 LAST HDL_TAP TRUE
J 0
(-1925 1475);
DISPLAY 0.872340 (-1925 1475);
DISPLAY INVISIBLE (-1925 1475);
FORCEPROP 1 LAST PATH I57
J 0
(-2252 1600);
DISPLAY 0.872340 (-2252 1600);
PAINT GREEN (-2252 1600);
DISPLAY INVISIBLE (-2252 1600);
FORCEADD TAP..1
(-2250 1900);
FORCEPROP 3 LASTPIN (-2300 1900) SIG_NAME M_H_CPU1_SB_DQ<13>
J 0
(-2290 1910);
DISPLAY 0.659574 (-2290 1910);
PAINT MONO (-2290 1910);
DISPLAY INVISIBLE (-2290 1910);
FORCEPROP 1 LASTPIN (-2300 1900) BN 13
J 0
(-2312 1908);
DISPLAY 0.680851 (-2312 1908);
PAINT GREEN (-2312 1908);
FORCEPROP 2 LAST CDS_LIB standard
J 0
(-2250 1900);
PAINT MONO (-2250 1900);
DISPLAY INVISIBLE (-2250 1900);
FORCEPROP 1 LAST BODY_TYPE PLUMBING
J 0
(-2250 1950);
DISPLAY 0.872340 (-2250 1950);
PAINT GREEN (-2250 1950);
DISPLAY INVISIBLE (-2250 1950);
FORCEPROP 1 LAST HDL_TAP TRUE
J 0
(-1925 1775);
DISPLAY 0.872340 (-1925 1775);
DISPLAY INVISIBLE (-1925 1775);
FORCEPROP 1 LAST PATH I58
J 0
(-2252 1900);
DISPLAY 0.872340 (-2252 1900);
PAINT GREEN (-2252 1900);
DISPLAY INVISIBLE (-2252 1900);
FORCEADD TAP..1
(-2250 2000);
FORCEPROP 3 LASTPIN (-2300 2000) SIG_NAME M_H_CPU1_SB_DQ<15>
J 0
(-2290 2010);
DISPLAY 0.659574 (-2290 2010);
PAINT MONO (-2290 2010);
DISPLAY INVISIBLE (-2290 2010);
FORCEPROP 1 LASTPIN (-2300 2000) BN 15
J 0
(-2312 2008);
DISPLAY 0.680851 (-2312 2008);
PAINT GREEN (-2312 2008);
FORCEPROP 2 LAST CDS_LIB standard
J 0
(-2250 2000);
PAINT MONO (-2250 2000);
DISPLAY INVISIBLE (-2250 2000);
FORCEPROP 1 LAST BODY_TYPE PLUMBING
J 0
(-2250 2050);
DISPLAY 0.872340 (-2250 2050);
PAINT GREEN (-2250 2050);
DISPLAY INVISIBLE (-2250 2050);
FORCEPROP 1 LAST HDL_TAP TRUE
J 0
(-1925 1875);
DISPLAY 0.872340 (-1925 1875);
DISPLAY INVISIBLE (-1925 1875);
FORCEPROP 1 LAST PATH I59
J 0
(-2252 2000);
DISPLAY 0.872340 (-2252 2000);
PAINT GREEN (-2252 2000);
DISPLAY INVISIBLE (-2252 2000);
FORCEADD OFFPAGE..1
(-4725 1950);
FORCEPROP 2 LAST $XR0 113 
J 0
(-4977 1950);
DISPLAY 0.638298 (-4977 1950);
PAINT MONO (-4977 1950);
FORCEPROP 2 LAST CDS_LIB standard
J 0
(-4725 1950);
PAINT MONO (-4725 1950);
DISPLAY INVISIBLE (-4725 1950);
FORCEPROP 1 LAST OFFPAGE TRUE
J 0
(-4400 1825);
DISPLAY 0.872340 (-4400 1825);
DISPLAY INVISIBLE (-4400 1825);
FORCEPROP 1 LAST COMMENT_BODY TRUE
J 0
(-4600 1850);
DISPLAY 0.872340 (-4600 1850);
PAINT GREEN (-4600 1850);
DISPLAY INVISIBLE (-4600 1850);
FORCEPROP 2 LAST PATH I6
J 0
(-4675 2025);
DISPLAY 1.021277 (-4675 2025);
DISPLAY INVISIBLE (-4675 2025);
FORCEADD TAP..1
(-2250 2050);
FORCEPROP 3 LASTPIN (-2300 2050) SIG_NAME M_H_CPU1_SB_DQ<16>
J 0
(-2290 2060);
DISPLAY 0.659574 (-2290 2060);
PAINT MONO (-2290 2060);
DISPLAY INVISIBLE (-2290 2060);
FORCEPROP 1 LASTPIN (-2300 2050) BN 16
J 0
(-2312 2058);
DISPLAY 0.680851 (-2312 2058);
PAINT GREEN (-2312 2058);
FORCEPROP 2 LAST CDS_LIB standard
J 0
(-2250 2050);
PAINT MONO (-2250 2050);
DISPLAY INVISIBLE (-2250 2050);
FORCEPROP 1 LAST BODY_TYPE PLUMBING
J 0
(-2250 2100);
DISPLAY 0.872340 (-2250 2100);
PAINT GREEN (-2250 2100);
DISPLAY INVISIBLE (-2250 2100);
FORCEPROP 1 LAST HDL_TAP TRUE
J 0
(-1925 1925);
DISPLAY 0.872340 (-1925 1925);
DISPLAY INVISIBLE (-1925 1925);
FORCEPROP 1 LAST PATH I60
J 0
(-2252 2050);
DISPLAY 0.872340 (-2252 2050);
PAINT GREEN (-2252 2050);
DISPLAY INVISIBLE (-2252 2050);
FORCEADD TAP..1
(-2250 1950);
FORCEPROP 3 LASTPIN (-2300 1950) SIG_NAME M_H_CPU1_SB_DQ<14>
J 0
(-2290 1960);
DISPLAY 0.659574 (-2290 1960);
PAINT MONO (-2290 1960);
DISPLAY INVISIBLE (-2290 1960);
FORCEPROP 1 LASTPIN (-2300 1950) BN 14
J 0
(-2312 1958);
DISPLAY 0.680851 (-2312 1958);
PAINT GREEN (-2312 1958);
FORCEPROP 2 LAST CDS_LIB standard
J 0
(-2250 1950);
PAINT MONO (-2250 1950);
DISPLAY INVISIBLE (-2250 1950);
FORCEPROP 1 LAST BODY_TYPE PLUMBING
J 0
(-2250 2000);
DISPLAY 0.872340 (-2250 2000);
PAINT GREEN (-2250 2000);
DISPLAY INVISIBLE (-2250 2000);
FORCEPROP 1 LAST HDL_TAP TRUE
J 0
(-1925 1825);
DISPLAY 0.872340 (-1925 1825);
DISPLAY INVISIBLE (-1925 1825);
FORCEPROP 1 LAST PATH I61
J 0
(-2252 1950);
DISPLAY 0.872340 (-2252 1950);
PAINT GREEN (-2252 1950);
DISPLAY INVISIBLE (-2252 1950);
FORCEADD TAP..1
(-2250 1850);
FORCEPROP 3 LASTPIN (-2300 1850) SIG_NAME M_H_CPU1_SB_DQ<12>
J 0
(-2290 1860);
DISPLAY 0.659574 (-2290 1860);
PAINT MONO (-2290 1860);
DISPLAY INVISIBLE (-2290 1860);
FORCEPROP 1 LASTPIN (-2300 1850) BN 12
J 0
(-2312 1858);
DISPLAY 0.680851 (-2312 1858);
PAINT GREEN (-2312 1858);
FORCEPROP 2 LAST CDS_LIB standard
J 0
(-2250 1850);
PAINT MONO (-2250 1850);
DISPLAY INVISIBLE (-2250 1850);
FORCEPROP 1 LAST BODY_TYPE PLUMBING
J 0
(-2250 1900);
DISPLAY 0.872340 (-2250 1900);
PAINT GREEN (-2250 1900);
DISPLAY INVISIBLE (-2250 1900);
FORCEPROP 1 LAST HDL_TAP TRUE
J 0
(-1925 1725);
DISPLAY 0.872340 (-1925 1725);
DISPLAY INVISIBLE (-1925 1725);
FORCEPROP 1 LAST PATH I62
J 0
(-2252 1850);
DISPLAY 0.872340 (-2252 1850);
PAINT GREEN (-2252 1850);
DISPLAY INVISIBLE (-2252 1850);
FORCEADD TAP..1
(-2250 2200);
FORCEPROP 3 LASTPIN (-2300 2200) SIG_NAME M_H_CPU1_SB_DQ<19>
J 0
(-2290 2210);
DISPLAY 0.659574 (-2290 2210);
PAINT MONO (-2290 2210);
DISPLAY INVISIBLE (-2290 2210);
FORCEPROP 1 LASTPIN (-2300 2200) BN 19
J 0
(-2312 2208);
DISPLAY 0.680851 (-2312 2208);
PAINT GREEN (-2312 2208);
FORCEPROP 2 LAST CDS_LIB standard
J 0
(-2250 2200);
PAINT MONO (-2250 2200);
DISPLAY INVISIBLE (-2250 2200);
FORCEPROP 1 LAST BODY_TYPE PLUMBING
J 0
(-2250 2250);
DISPLAY 0.872340 (-2250 2250);
PAINT GREEN (-2250 2250);
DISPLAY INVISIBLE (-2250 2250);
FORCEPROP 1 LAST HDL_TAP TRUE
J 0
(-1925 2075);
DISPLAY 0.872340 (-1925 2075);
DISPLAY INVISIBLE (-1925 2075);
FORCEPROP 1 LAST PATH I63
J 0
(-2252 2200);
DISPLAY 0.872340 (-2252 2200);
PAINT GREEN (-2252 2200);
DISPLAY INVISIBLE (-2252 2200);
FORCEADD TAP..1
(-2250 2250);
FORCEPROP 3 LASTPIN (-2300 2250) SIG_NAME M_H_CPU1_SB_DQ<20>
J 0
(-2290 2260);
DISPLAY 0.659574 (-2290 2260);
PAINT MONO (-2290 2260);
DISPLAY INVISIBLE (-2290 2260);
FORCEPROP 1 LASTPIN (-2300 2250) BN 20
J 0
(-2312 2258);
DISPLAY 0.680851 (-2312 2258);
PAINT GREEN (-2312 2258);
FORCEPROP 2 LAST CDS_LIB standard
J 0
(-2250 2250);
PAINT MONO (-2250 2250);
DISPLAY INVISIBLE (-2250 2250);
FORCEPROP 1 LAST BODY_TYPE PLUMBING
J 0
(-2250 2300);
DISPLAY 0.872340 (-2250 2300);
PAINT GREEN (-2250 2300);
DISPLAY INVISIBLE (-2250 2300);
FORCEPROP 1 LAST HDL_TAP TRUE
J 0
(-1925 2125);
DISPLAY 0.872340 (-1925 2125);
DISPLAY INVISIBLE (-1925 2125);
FORCEPROP 1 LAST PATH I64
J 0
(-2252 2250);
DISPLAY 0.872340 (-2252 2250);
PAINT GREEN (-2252 2250);
DISPLAY INVISIBLE (-2252 2250);
FORCEADD TAP..1
(-2250 2300);
FORCEPROP 3 LASTPIN (-2300 2300) SIG_NAME M_H_CPU1_SB_DQ<21>
J 0
(-2290 2310);
DISPLAY 0.659574 (-2290 2310);
PAINT MONO (-2290 2310);
DISPLAY INVISIBLE (-2290 2310);
FORCEPROP 1 LASTPIN (-2300 2300) BN 21
J 0
(-2312 2308);
DISPLAY 0.680851 (-2312 2308);
PAINT GREEN (-2312 2308);
FORCEPROP 2 LAST CDS_LIB standard
J 0
(-2250 2300);
PAINT MONO (-2250 2300);
DISPLAY INVISIBLE (-2250 2300);
FORCEPROP 1 LAST BODY_TYPE PLUMBING
J 0
(-2250 2350);
DISPLAY 0.872340 (-2250 2350);
PAINT GREEN (-2250 2350);
DISPLAY INVISIBLE (-2250 2350);
FORCEPROP 1 LAST HDL_TAP TRUE
J 0
(-1925 2175);
DISPLAY 0.872340 (-1925 2175);
DISPLAY INVISIBLE (-1925 2175);
FORCEPROP 1 LAST PATH I65
J 0
(-2252 2300);
DISPLAY 0.872340 (-2252 2300);
PAINT GREEN (-2252 2300);
DISPLAY INVISIBLE (-2252 2300);
FORCEADD TAP..1
(-2250 2150);
FORCEPROP 3 LASTPIN (-2300 2150) SIG_NAME M_H_CPU1_SB_DQ<18>
J 0
(-2290 2160);
DISPLAY 0.659574 (-2290 2160);
PAINT MONO (-2290 2160);
DISPLAY INVISIBLE (-2290 2160);
FORCEPROP 1 LASTPIN (-2300 2150) BN 18
J 0
(-2312 2158);
DISPLAY 0.680851 (-2312 2158);
PAINT GREEN (-2312 2158);
FORCEPROP 2 LAST CDS_LIB standard
J 0
(-2250 2150);
PAINT MONO (-2250 2150);
DISPLAY INVISIBLE (-2250 2150);
FORCEPROP 1 LAST BODY_TYPE PLUMBING
J 0
(-2250 2200);
DISPLAY 0.872340 (-2250 2200);
PAINT GREEN (-2250 2200);
DISPLAY INVISIBLE (-2250 2200);
FORCEPROP 1 LAST HDL_TAP TRUE
J 0
(-1925 2025);
DISPLAY 0.872340 (-1925 2025);
DISPLAY INVISIBLE (-1925 2025);
FORCEPROP 1 LAST PATH I66
J 0
(-2252 2150);
DISPLAY 0.872340 (-2252 2150);
PAINT GREEN (-2252 2150);
DISPLAY INVISIBLE (-2252 2150);
FORCEADD TAP..1
(-2250 2100);
FORCEPROP 3 LASTPIN (-2300 2100) SIG_NAME M_H_CPU1_SB_DQ<17>
J 0
(-2290 2110);
DISPLAY 0.659574 (-2290 2110);
PAINT MONO (-2290 2110);
DISPLAY INVISIBLE (-2290 2110);
FORCEPROP 1 LASTPIN (-2300 2100) BN 17
J 0
(-2312 2108);
DISPLAY 0.680851 (-2312 2108);
PAINT GREEN (-2312 2108);
FORCEPROP 2 LAST CDS_LIB standard
J 0
(-2250 2100);
PAINT MONO (-2250 2100);
DISPLAY INVISIBLE (-2250 2100);
FORCEPROP 1 LAST BODY_TYPE PLUMBING
J 0
(-2250 2150);
DISPLAY 0.872340 (-2250 2150);
PAINT GREEN (-2250 2150);
DISPLAY INVISIBLE (-2250 2150);
FORCEPROP 1 LAST HDL_TAP TRUE
J 0
(-1925 1975);
DISPLAY 0.872340 (-1925 1975);
DISPLAY INVISIBLE (-1925 1975);
FORCEPROP 1 LAST PATH I67
J 0
(-2252 2100);
DISPLAY 0.872340 (-2252 2100);
PAINT GREEN (-2252 2100);
DISPLAY INVISIBLE (-2252 2100);
FORCEADD TAP..1
R 2
(-3900 4350);
FORCEPROP 3 LASTPIN (-3850 4350) SIG_NAME M_H_CPU1_SA_CA<4>
J 0
(-3840 4360);
DISPLAY 0.659574 (-3840 4360);
PAINT MONO (-3840 4360);
DISPLAY INVISIBLE (-3840 4360);
FORCEPROP 1 LASTPIN (-3850 4350) BN 4
J 2
(-3838 4358);
DISPLAY 0.680851 (-3838 4358);
PAINT GREEN (-3838 4358);
FORCEPROP 2 LAST CDS_LIB standard
J 0
(-3900 4350);
DISPLAY INVISIBLE (-3900 4350);
FORCEPROP 1 LAST BODY_TYPE PLUMBING
J 2
(-3900 4400);
DISPLAY 0.872340 (-3900 4400);
PAINT GREEN (-3900 4400);
DISPLAY INVISIBLE (-3900 4400);
FORCEPROP 1 LAST HDL_TAP TRUE
J 2
(-4225 4225);
DISPLAY 0.872340 (-4225 4225);
DISPLAY INVISIBLE (-4225 4225);
FORCEPROP 1 LAST PATH I68
J 2
(-3898 4350);
DISPLAY 0.872340 (-3898 4350);
PAINT GREEN (-3898 4350);
DISPLAY INVISIBLE (-3898 4350);
FORCEADD TAP..1
(-2250 2500);
FORCEPROP 3 LASTPIN (-2300 2500) SIG_NAME M_H_CPU1_SB_DQ<25>
J 0
(-2290 2510);
DISPLAY 0.659574 (-2290 2510);
PAINT MONO (-2290 2510);
DISPLAY INVISIBLE (-2290 2510);
FORCEPROP 1 LASTPIN (-2300 2500) BN 25
J 0
(-2312 2508);
DISPLAY 0.680851 (-2312 2508);
PAINT GREEN (-2312 2508);
FORCEPROP 2 LAST CDS_LIB standard
J 0
(-2250 2500);
DISPLAY INVISIBLE (-2250 2500);
FORCEPROP 1 LAST BODY_TYPE PLUMBING
J 0
(-2250 2550);
DISPLAY 0.872340 (-2250 2550);
PAINT GREEN (-2250 2550);
DISPLAY INVISIBLE (-2250 2550);
FORCEPROP 1 LAST HDL_TAP TRUE
J 0
(-1925 2375);
DISPLAY 0.872340 (-1925 2375);
DISPLAY INVISIBLE (-1925 2375);
FORCEPROP 1 LAST PATH I69
J 0
(-2252 2500);
DISPLAY 0.872340 (-2252 2500);
PAINT GREEN (-2252 2500);
DISPLAY INVISIBLE (-2252 2500);
FORCEADD OFFPAGE..1
(-4825 2100);
FORCEPROP 2 LAST $XR1 112 
J 0
(-5166 2100);
DISPLAY 0.638298 (-5166 2100);
PAINT MONO (-5166 2100);
FORCEPROP 2 LAST $XR0 58 
J 0
(-5046 2100);
DISPLAY 0.638298 (-5046 2100);
PAINT MONO (-5046 2100);
FORCEPROP 2 LAST CDS_LIB standard
J 0
(-4825 2100);
PAINT MONO (-4825 2100);
DISPLAY INVISIBLE (-4825 2100);
FORCEPROP 1 LAST OFFPAGE TRUE
J 0
(-4500 1975);
DISPLAY 0.872340 (-4500 1975);
DISPLAY INVISIBLE (-4500 1975);
FORCEPROP 1 LAST COMMENT_BODY TRUE
J 0
(-4700 2000);
DISPLAY 0.872340 (-4700 2000);
PAINT GREEN (-4700 2000);
DISPLAY INVISIBLE (-4700 2000);
FORCEPROP 2 LAST PATH I7
J 0
(-4775 2175);
DISPLAY 1.021277 (-4775 2175);
DISPLAY INVISIBLE (-4775 2175);
FORCEADD TAP..1
(-2250 2550);
FORCEPROP 3 LASTPIN (-2300 2550) SIG_NAME M_H_CPU1_SB_DQ<26>
J 0
(-2290 2560);
DISPLAY 0.659574 (-2290 2560);
PAINT MONO (-2290 2560);
DISPLAY INVISIBLE (-2290 2560);
FORCEPROP 1 LASTPIN (-2300 2550) BN 26
J 0
(-2312 2558);
DISPLAY 0.680851 (-2312 2558);
PAINT GREEN (-2312 2558);
FORCEPROP 2 LAST CDS_LIB standard
J 0
(-2250 2550);
DISPLAY INVISIBLE (-2250 2550);
FORCEPROP 1 LAST BODY_TYPE PLUMBING
J 0
(-2250 2600);
DISPLAY 0.872340 (-2250 2600);
PAINT GREEN (-2250 2600);
DISPLAY INVISIBLE (-2250 2600);
FORCEPROP 1 LAST HDL_TAP TRUE
J 0
(-1925 2425);
DISPLAY 0.872340 (-1925 2425);
DISPLAY INVISIBLE (-1925 2425);
FORCEPROP 1 LAST PATH I70
J 0
(-2252 2550);
DISPLAY 0.872340 (-2252 2550);
PAINT GREEN (-2252 2550);
DISPLAY INVISIBLE (-2252 2550);
FORCEADD TAP..1
(-2250 2450);
FORCEPROP 3 LASTPIN (-2300 2450) SIG_NAME M_H_CPU1_SB_DQ<24>
J 0
(-2290 2460);
DISPLAY 0.659574 (-2290 2460);
PAINT MONO (-2290 2460);
DISPLAY INVISIBLE (-2290 2460);
FORCEPROP 1 LASTPIN (-2300 2450) BN 24
J 0
(-2312 2458);
DISPLAY 0.680851 (-2312 2458);
PAINT GREEN (-2312 2458);
FORCEPROP 2 LAST CDS_LIB standard
J 0
(-2250 2450);
DISPLAY INVISIBLE (-2250 2450);
FORCEPROP 1 LAST BODY_TYPE PLUMBING
J 0
(-2250 2500);
DISPLAY 0.872340 (-2250 2500);
PAINT GREEN (-2250 2500);
DISPLAY INVISIBLE (-2250 2500);
FORCEPROP 1 LAST HDL_TAP TRUE
J 0
(-1925 2325);
DISPLAY 0.872340 (-1925 2325);
DISPLAY INVISIBLE (-1925 2325);
FORCEPROP 1 LAST PATH I71
J 0
(-2252 2450);
DISPLAY 0.872340 (-2252 2450);
PAINT GREEN (-2252 2450);
DISPLAY INVISIBLE (-2252 2450);
FORCEADD TAP..1
(-2250 2400);
FORCEPROP 3 LASTPIN (-2300 2400) SIG_NAME M_H_CPU1_SB_DQ<23>
J 0
(-2290 2410);
DISPLAY 0.659574 (-2290 2410);
PAINT MONO (-2290 2410);
DISPLAY INVISIBLE (-2290 2410);
FORCEPROP 1 LASTPIN (-2300 2400) BN 23
J 0
(-2312 2408);
DISPLAY 0.680851 (-2312 2408);
PAINT GREEN (-2312 2408);
FORCEPROP 2 LAST CDS_LIB standard
J 0
(-2250 2400);
DISPLAY INVISIBLE (-2250 2400);
FORCEPROP 1 LAST BODY_TYPE PLUMBING
J 0
(-2250 2450);
DISPLAY 0.872340 (-2250 2450);
PAINT GREEN (-2250 2450);
DISPLAY INVISIBLE (-2250 2450);
FORCEPROP 1 LAST HDL_TAP TRUE
J 0
(-1925 2275);
DISPLAY 0.872340 (-1925 2275);
DISPLAY INVISIBLE (-1925 2275);
FORCEPROP 1 LAST PATH I72
J 0
(-2252 2400);
DISPLAY 0.872340 (-2252 2400);
PAINT GREEN (-2252 2400);
DISPLAY INVISIBLE (-2252 2400);
FORCEADD TAP..1
(-2250 2350);
FORCEPROP 3 LASTPIN (-2300 2350) SIG_NAME M_H_CPU1_SB_DQ<22>
J 0
(-2290 2360);
DISPLAY 0.659574 (-2290 2360);
PAINT MONO (-2290 2360);
DISPLAY INVISIBLE (-2290 2360);
FORCEPROP 1 LASTPIN (-2300 2350) BN 22
J 0
(-2312 2358);
DISPLAY 0.680851 (-2312 2358);
PAINT GREEN (-2312 2358);
FORCEPROP 2 LAST CDS_LIB standard
J 0
(-2250 2350);
DISPLAY INVISIBLE (-2250 2350);
FORCEPROP 1 LAST BODY_TYPE PLUMBING
J 0
(-2250 2400);
DISPLAY 0.872340 (-2250 2400);
PAINT GREEN (-2250 2400);
DISPLAY INVISIBLE (-2250 2400);
FORCEPROP 1 LAST HDL_TAP TRUE
J 0
(-1925 2225);
DISPLAY 0.872340 (-1925 2225);
DISPLAY INVISIBLE (-1925 2225);
FORCEPROP 1 LAST PATH I73
J 0
(-2252 2350);
DISPLAY 0.872340 (-2252 2350);
PAINT GREEN (-2252 2350);
DISPLAY INVISIBLE (-2252 2350);
FORCEADD TAP..1
(-2250 2750);
FORCEPROP 3 LASTPIN (-2300 2750) SIG_NAME M_H_CPU1_SB_DQ<30>
J 0
(-2290 2760);
DISPLAY 0.659574 (-2290 2760);
PAINT MONO (-2290 2760);
DISPLAY INVISIBLE (-2290 2760);
FORCEPROP 1 LASTPIN (-2300 2750) BN 30
J 0
(-2312 2758);
DISPLAY 0.680851 (-2312 2758);
PAINT GREEN (-2312 2758);
FORCEPROP 2 LAST CDS_LIB standard
J 0
(-2250 2750);
DISPLAY INVISIBLE (-2250 2750);
FORCEPROP 1 LAST BODY_TYPE PLUMBING
J 0
(-2250 2800);
DISPLAY 0.872340 (-2250 2800);
PAINT GREEN (-2250 2800);
DISPLAY INVISIBLE (-2250 2800);
FORCEPROP 1 LAST HDL_TAP TRUE
J 0
(-1925 2625);
DISPLAY 0.872340 (-1925 2625);
DISPLAY INVISIBLE (-1925 2625);
FORCEPROP 1 LAST PATH I74
J 0
(-2252 2750);
DISPLAY 0.872340 (-2252 2750);
PAINT GREEN (-2252 2750);
DISPLAY INVISIBLE (-2252 2750);
FORCEADD TAP..1
(-2250 2800);
FORCEPROP 3 LASTPIN (-2300 2800) SIG_NAME M_H_CPU1_SB_DQ<31>
J 0
(-2290 2810);
DISPLAY 0.659574 (-2290 2810);
PAINT MONO (-2290 2810);
DISPLAY INVISIBLE (-2290 2810);
FORCEPROP 1 LASTPIN (-2300 2800) BN 31
J 0
(-2312 2808);
DISPLAY 0.680851 (-2312 2808);
PAINT GREEN (-2312 2808);
FORCEPROP 2 LAST CDS_LIB standard
J 0
(-2250 2800);
DISPLAY INVISIBLE (-2250 2800);
FORCEPROP 1 LAST BODY_TYPE PLUMBING
J 0
(-2250 2850);
DISPLAY 0.872340 (-2250 2850);
PAINT GREEN (-2250 2850);
DISPLAY INVISIBLE (-2250 2850);
FORCEPROP 1 LAST HDL_TAP TRUE
J 0
(-1925 2675);
DISPLAY 0.872340 (-1925 2675);
DISPLAY INVISIBLE (-1925 2675);
FORCEPROP 1 LAST PATH I75
J 0
(-2252 2800);
DISPLAY 0.872340 (-2252 2800);
PAINT GREEN (-2252 2800);
DISPLAY INVISIBLE (-2252 2800);
FORCEADD TAP..1
(-2250 2700);
FORCEPROP 3 LASTPIN (-2300 2700) SIG_NAME M_H_CPU1_SB_DQ<29>
J 0
(-2290 2710);
DISPLAY 0.659574 (-2290 2710);
PAINT MONO (-2290 2710);
DISPLAY INVISIBLE (-2290 2710);
FORCEPROP 1 LASTPIN (-2300 2700) BN 29
J 0
(-2312 2708);
DISPLAY 0.680851 (-2312 2708);
PAINT GREEN (-2312 2708);
FORCEPROP 2 LAST CDS_LIB standard
J 0
(-2250 2700);
DISPLAY INVISIBLE (-2250 2700);
FORCEPROP 1 LAST BODY_TYPE PLUMBING
J 0
(-2250 2750);
DISPLAY 0.872340 (-2250 2750);
PAINT GREEN (-2250 2750);
DISPLAY INVISIBLE (-2250 2750);
FORCEPROP 1 LAST HDL_TAP TRUE
J 0
(-1925 2575);
DISPLAY 0.872340 (-1925 2575);
DISPLAY INVISIBLE (-1925 2575);
FORCEPROP 1 LAST PATH I76
J 0
(-2252 2700);
DISPLAY 0.872340 (-2252 2700);
PAINT GREEN (-2252 2700);
DISPLAY INVISIBLE (-2252 2700);
FORCEADD TAP..1
(-2250 2600);
FORCEPROP 3 LASTPIN (-2300 2600) SIG_NAME M_H_CPU1_SB_DQ<27>
J 0
(-2290 2610);
DISPLAY 0.659574 (-2290 2610);
PAINT MONO (-2290 2610);
DISPLAY INVISIBLE (-2290 2610);
FORCEPROP 1 LASTPIN (-2300 2600) BN 27
J 0
(-2312 2608);
DISPLAY 0.680851 (-2312 2608);
PAINT GREEN (-2312 2608);
FORCEPROP 2 LAST CDS_LIB standard
J 0
(-2250 2600);
DISPLAY INVISIBLE (-2250 2600);
FORCEPROP 1 LAST BODY_TYPE PLUMBING
J 0
(-2250 2650);
DISPLAY 0.872340 (-2250 2650);
PAINT GREEN (-2250 2650);
DISPLAY INVISIBLE (-2250 2650);
FORCEPROP 1 LAST HDL_TAP TRUE
J 0
(-1925 2475);
DISPLAY 0.872340 (-1925 2475);
DISPLAY INVISIBLE (-1925 2475);
FORCEPROP 1 LAST PATH I77
J 0
(-2252 2600);
DISPLAY 0.872340 (-2252 2600);
PAINT GREEN (-2252 2600);
DISPLAY INVISIBLE (-2252 2600);
FORCEADD TAP..1
(-2250 2650);
FORCEPROP 3 LASTPIN (-2300 2650) SIG_NAME M_H_CPU1_SB_DQ<28>
J 0
(-2290 2660);
DISPLAY 0.659574 (-2290 2660);
PAINT MONO (-2290 2660);
DISPLAY INVISIBLE (-2290 2660);
FORCEPROP 1 LASTPIN (-2300 2650) BN 28
J 0
(-2312 2658);
DISPLAY 0.680851 (-2312 2658);
PAINT GREEN (-2312 2658);
FORCEPROP 2 LAST CDS_LIB standard
J 0
(-2250 2650);
DISPLAY INVISIBLE (-2250 2650);
FORCEPROP 1 LAST BODY_TYPE PLUMBING
J 0
(-2250 2700);
DISPLAY 0.872340 (-2250 2700);
PAINT GREEN (-2250 2700);
DISPLAY INVISIBLE (-2250 2700);
FORCEPROP 1 LAST HDL_TAP TRUE
J 0
(-1925 2525);
DISPLAY 0.872340 (-1925 2525);
DISPLAY INVISIBLE (-1925 2525);
FORCEPROP 1 LAST PATH I78
J 0
(-2252 2650);
DISPLAY 0.872340 (-2252 2650);
PAINT GREEN (-2252 2650);
DISPLAY INVISIBLE (-2252 2650);
FORCEADD TAP..1
(-2250 2900);
FORCEPROP 3 LASTPIN (-2300 2900) SIG_NAME M_H_CPU1_SA_DQ<0>
J 0
(-2290 2910);
DISPLAY 0.659574 (-2290 2910);
PAINT MONO (-2290 2910);
DISPLAY INVISIBLE (-2290 2910);
FORCEPROP 1 LASTPIN (-2300 2900) BN 0
J 0
(-2312 2908);
DISPLAY 0.680851 (-2312 2908);
PAINT GREEN (-2312 2908);
FORCEPROP 2 LAST CDS_LIB standard
J 0
(-2250 2900);
PAINT MONO (-2250 2900);
DISPLAY INVISIBLE (-2250 2900);
FORCEPROP 1 LAST BODY_TYPE PLUMBING
J 0
(-2250 2950);
DISPLAY 0.872340 (-2250 2950);
PAINT GREEN (-2250 2950);
DISPLAY INVISIBLE (-2250 2950);
FORCEPROP 1 LAST HDL_TAP TRUE
J 0
(-1925 2775);
DISPLAY 0.872340 (-1925 2775);
DISPLAY INVISIBLE (-1925 2775);
FORCEPROP 1 LAST PATH I79
J 0
(-2252 2900);
DISPLAY 0.872340 (-2252 2900);
PAINT GREEN (-2252 2900);
DISPLAY INVISIBLE (-2252 2900);
FORCEADD OFFPAGE..1
(-4825 2200);
FORCEPROP 2 LAST $XR3 112 
J 0
(-5197 2164);
DISPLAY 0.638298 (-5197 2164);
PAINT MONO (-5197 2164);
FORCEPROP 2 LAST $XR2 111 
J 0
(-5077 2164);
DISPLAY 0.638298 (-5077 2164);
PAINT MONO (-5077 2164);
FORCEPROP 2 LAST $XR1 110 
J 0
(-5197 2200);
DISPLAY 0.638298 (-5197 2200);
PAINT MONO (-5197 2200);
FORCEPROP 2 LAST $XR0 130 
J 0
(-5077 2200);
DISPLAY 0.638298 (-5077 2200);
PAINT MONO (-5077 2200);
FORCEPROP 2 LAST CDS_LIB standard
J 0
(-4825 2200);
PAINT MONO (-4825 2200);
DISPLAY INVISIBLE (-4825 2200);
FORCEPROP 1 LAST OFFPAGE TRUE
J 0
(-4500 2075);
DISPLAY 0.872340 (-4500 2075);
DISPLAY INVISIBLE (-4500 2075);
FORCEPROP 1 LAST COMMENT_BODY TRUE
J 0
(-4700 2100);
DISPLAY 0.872340 (-4700 2100);
PAINT GREEN (-4700 2100);
DISPLAY INVISIBLE (-4700 2100);
FORCEPROP 2 LAST PATH I8
J 0
(-4775 2275);
DISPLAY 1.021277 (-4775 2275);
DISPLAY INVISIBLE (-4775 2275);
FORCEADD TAP..1
(-2250 3000);
FORCEPROP 3 LASTPIN (-2300 3000) SIG_NAME M_H_CPU1_SA_DQ<2>
J 0
(-2290 3010);
DISPLAY 0.659574 (-2290 3010);
PAINT MONO (-2290 3010);
DISPLAY INVISIBLE (-2290 3010);
FORCEPROP 1 LASTPIN (-2300 3000) BN 2
J 0
(-2312 3008);
DISPLAY 0.680851 (-2312 3008);
PAINT GREEN (-2312 3008);
FORCEPROP 2 LAST CDS_LIB standard
J 0
(-2250 3000);
PAINT MONO (-2250 3000);
DISPLAY INVISIBLE (-2250 3000);
FORCEPROP 1 LAST BODY_TYPE PLUMBING
J 0
(-2250 3050);
DISPLAY 0.872340 (-2250 3050);
PAINT GREEN (-2250 3050);
DISPLAY INVISIBLE (-2250 3050);
FORCEPROP 1 LAST HDL_TAP TRUE
J 0
(-1925 2875);
DISPLAY 0.872340 (-1925 2875);
DISPLAY INVISIBLE (-1925 2875);
FORCEPROP 1 LAST PATH I80
J 0
(-2252 3000);
DISPLAY 0.872340 (-2252 3000);
PAINT GREEN (-2252 3000);
DISPLAY INVISIBLE (-2252 3000);
FORCEADD TAP..1
(-2250 3050);
FORCEPROP 3 LASTPIN (-2300 3050) SIG_NAME M_H_CPU1_SA_DQ<3>
J 0
(-2290 3060);
DISPLAY 0.659574 (-2290 3060);
PAINT MONO (-2290 3060);
DISPLAY INVISIBLE (-2290 3060);
FORCEPROP 1 LASTPIN (-2300 3050) BN 3
J 0
(-2312 3058);
DISPLAY 0.680851 (-2312 3058);
PAINT GREEN (-2312 3058);
FORCEPROP 2 LAST CDS_LIB standard
J 0
(-2250 3050);
PAINT MONO (-2250 3050);
DISPLAY INVISIBLE (-2250 3050);
FORCEPROP 1 LAST BODY_TYPE PLUMBING
J 0
(-2250 3100);
DISPLAY 0.872340 (-2250 3100);
PAINT GREEN (-2250 3100);
DISPLAY INVISIBLE (-2250 3100);
FORCEPROP 1 LAST HDL_TAP TRUE
J 0
(-1925 2925);
DISPLAY 0.872340 (-1925 2925);
DISPLAY INVISIBLE (-1925 2925);
FORCEPROP 1 LAST PATH I81
J 0
(-2252 3050);
DISPLAY 0.872340 (-2252 3050);
PAINT GREEN (-2252 3050);
DISPLAY INVISIBLE (-2252 3050);
FORCEADD TAP..1
(-2250 2950);
FORCEPROP 3 LASTPIN (-2300 2950) SIG_NAME M_H_CPU1_SA_DQ<1>
J 0
(-2290 2960);
DISPLAY 0.659574 (-2290 2960);
PAINT MONO (-2290 2960);
DISPLAY INVISIBLE (-2290 2960);
FORCEPROP 1 LASTPIN (-2300 2950) BN 1
J 0
(-2312 2958);
DISPLAY 0.680851 (-2312 2958);
PAINT GREEN (-2312 2958);
FORCEPROP 2 LAST CDS_LIB standard
J 0
(-2250 2950);
PAINT MONO (-2250 2950);
DISPLAY INVISIBLE (-2250 2950);
FORCEPROP 1 LAST BODY_TYPE PLUMBING
J 0
(-2250 3000);
DISPLAY 0.872340 (-2250 3000);
PAINT GREEN (-2250 3000);
DISPLAY INVISIBLE (-2250 3000);
FORCEPROP 1 LAST HDL_TAP TRUE
J 0
(-1925 2825);
DISPLAY 0.872340 (-1925 2825);
DISPLAY INVISIBLE (-1925 2825);
FORCEPROP 1 LAST PATH I82
J 0
(-2252 2950);
DISPLAY 0.872340 (-2252 2950);
PAINT GREEN (-2252 2950);
DISPLAY INVISIBLE (-2252 2950);
FORCEADD TAP..1
(-2250 3200);
FORCEPROP 3 LASTPIN (-2300 3200) SIG_NAME M_H_CPU1_SA_DQ<6>
J 0
(-2290 3210);
DISPLAY 0.659574 (-2290 3210);
PAINT MONO (-2290 3210);
DISPLAY INVISIBLE (-2290 3210);
FORCEPROP 1 LASTPIN (-2300 3200) BN 6
J 0
(-2312 3208);
DISPLAY 0.680851 (-2312 3208);
PAINT GREEN (-2312 3208);
FORCEPROP 2 LAST CDS_LIB standard
J 0
(-2250 3200);
PAINT MONO (-2250 3200);
DISPLAY INVISIBLE (-2250 3200);
FORCEPROP 1 LAST BODY_TYPE PLUMBING
J 0
(-2250 3250);
DISPLAY 0.872340 (-2250 3250);
PAINT GREEN (-2250 3250);
DISPLAY INVISIBLE (-2250 3250);
FORCEPROP 1 LAST HDL_TAP TRUE
J 0
(-1925 3075);
DISPLAY 0.872340 (-1925 3075);
DISPLAY INVISIBLE (-1925 3075);
FORCEPROP 1 LAST PATH I83
J 0
(-2252 3200);
DISPLAY 0.872340 (-2252 3200);
PAINT GREEN (-2252 3200);
DISPLAY INVISIBLE (-2252 3200);
FORCEADD TAP..1
(-2250 3300);
FORCEPROP 3 LASTPIN (-2300 3300) SIG_NAME M_H_CPU1_SA_DQ<8>
J 0
(-2290 3310);
DISPLAY 0.659574 (-2290 3310);
PAINT MONO (-2290 3310);
DISPLAY INVISIBLE (-2290 3310);
FORCEPROP 1 LASTPIN (-2300 3300) BN 8
J 0
(-2312 3308);
DISPLAY 0.680851 (-2312 3308);
PAINT GREEN (-2312 3308);
FORCEPROP 2 LAST CDS_LIB standard
J 0
(-2250 3300);
PAINT MONO (-2250 3300);
DISPLAY INVISIBLE (-2250 3300);
FORCEPROP 1 LAST BODY_TYPE PLUMBING
J 0
(-2250 3350);
DISPLAY 0.872340 (-2250 3350);
PAINT GREEN (-2250 3350);
DISPLAY INVISIBLE (-2250 3350);
FORCEPROP 1 LAST HDL_TAP TRUE
J 0
(-1925 3175);
DISPLAY 0.872340 (-1925 3175);
DISPLAY INVISIBLE (-1925 3175);
FORCEPROP 1 LAST PATH I84
J 0
(-2252 3300);
DISPLAY 0.872340 (-2252 3300);
PAINT GREEN (-2252 3300);
DISPLAY INVISIBLE (-2252 3300);
FORCEADD TAP..1
(-2250 3250);
FORCEPROP 3 LASTPIN (-2300 3250) SIG_NAME M_H_CPU1_SA_DQ<7>
J 0
(-2290 3260);
DISPLAY 0.659574 (-2290 3260);
PAINT MONO (-2290 3260);
DISPLAY INVISIBLE (-2290 3260);
FORCEPROP 1 LASTPIN (-2300 3250) BN 7
J 0
(-2312 3258);
DISPLAY 0.680851 (-2312 3258);
PAINT GREEN (-2312 3258);
FORCEPROP 2 LAST CDS_LIB standard
J 0
(-2250 3250);
PAINT MONO (-2250 3250);
DISPLAY INVISIBLE (-2250 3250);
FORCEPROP 1 LAST BODY_TYPE PLUMBING
J 0
(-2250 3300);
DISPLAY 0.872340 (-2250 3300);
PAINT GREEN (-2250 3300);
DISPLAY INVISIBLE (-2250 3300);
FORCEPROP 1 LAST HDL_TAP TRUE
J 0
(-1925 3125);
DISPLAY 0.872340 (-1925 3125);
DISPLAY INVISIBLE (-1925 3125);
FORCEPROP 1 LAST PATH I85
J 0
(-2252 3250);
DISPLAY 0.872340 (-2252 3250);
PAINT GREEN (-2252 3250);
DISPLAY INVISIBLE (-2252 3250);
FORCEADD TAP..1
(-2250 3150);
FORCEPROP 3 LASTPIN (-2300 3150) SIG_NAME M_H_CPU1_SA_DQ<5>
J 0
(-2290 3160);
DISPLAY 0.659574 (-2290 3160);
PAINT MONO (-2290 3160);
DISPLAY INVISIBLE (-2290 3160);
FORCEPROP 1 LASTPIN (-2300 3150) BN 5
J 0
(-2312 3158);
DISPLAY 0.680851 (-2312 3158);
PAINT GREEN (-2312 3158);
FORCEPROP 2 LAST CDS_LIB standard
J 0
(-2250 3150);
PAINT MONO (-2250 3150);
DISPLAY INVISIBLE (-2250 3150);
FORCEPROP 1 LAST BODY_TYPE PLUMBING
J 0
(-2250 3200);
DISPLAY 0.872340 (-2250 3200);
PAINT GREEN (-2250 3200);
DISPLAY INVISIBLE (-2250 3200);
FORCEPROP 1 LAST HDL_TAP TRUE
J 0
(-1925 3025);
DISPLAY 0.872340 (-1925 3025);
DISPLAY INVISIBLE (-1925 3025);
FORCEPROP 1 LAST PATH I86
J 0
(-2252 3150);
DISPLAY 0.872340 (-2252 3150);
PAINT GREEN (-2252 3150);
DISPLAY INVISIBLE (-2252 3150);
FORCEADD TAP..1
(-2250 3100);
FORCEPROP 3 LASTPIN (-2300 3100) SIG_NAME M_H_CPU1_SA_DQ<4>
J 0
(-2290 3110);
DISPLAY 0.659574 (-2290 3110);
PAINT MONO (-2290 3110);
DISPLAY INVISIBLE (-2290 3110);
FORCEPROP 1 LASTPIN (-2300 3100) BN 4
J 0
(-2312 3108);
DISPLAY 0.680851 (-2312 3108);
PAINT GREEN (-2312 3108);
FORCEPROP 2 LAST CDS_LIB standard
J 0
(-2250 3100);
PAINT MONO (-2250 3100);
DISPLAY INVISIBLE (-2250 3100);
FORCEPROP 1 LAST BODY_TYPE PLUMBING
J 0
(-2250 3150);
DISPLAY 0.872340 (-2250 3150);
PAINT GREEN (-2250 3150);
DISPLAY INVISIBLE (-2250 3150);
FORCEPROP 1 LAST HDL_TAP TRUE
J 0
(-1925 2975);
DISPLAY 0.872340 (-1925 2975);
DISPLAY INVISIBLE (-1925 2975);
FORCEPROP 1 LAST PATH I87
J 0
(-2252 3100);
DISPLAY 0.872340 (-2252 3100);
PAINT GREEN (-2252 3100);
DISPLAY INVISIBLE (-2252 3100);
FORCEADD TAP..1
(-2250 3400);
FORCEPROP 3 LASTPIN (-2300 3400) SIG_NAME M_H_CPU1_SA_DQ<10>
J 0
(-2290 3410);
DISPLAY 0.659574 (-2290 3410);
PAINT MONO (-2290 3410);
DISPLAY INVISIBLE (-2290 3410);
FORCEPROP 1 LASTPIN (-2300 3400) BN 10
J 0
(-2312 3408);
DISPLAY 0.680851 (-2312 3408);
PAINT GREEN (-2312 3408);
FORCEPROP 2 LAST CDS_LIB standard
J 0
(-2250 3400);
PAINT MONO (-2250 3400);
DISPLAY INVISIBLE (-2250 3400);
FORCEPROP 1 LAST BODY_TYPE PLUMBING
J 0
(-2250 3450);
DISPLAY 0.872340 (-2250 3450);
PAINT GREEN (-2250 3450);
DISPLAY INVISIBLE (-2250 3450);
FORCEPROP 1 LAST HDL_TAP TRUE
J 0
(-1925 3275);
DISPLAY 0.872340 (-1925 3275);
DISPLAY INVISIBLE (-1925 3275);
FORCEPROP 1 LAST PATH I88
J 0
(-2252 3400);
DISPLAY 0.872340 (-2252 3400);
PAINT GREEN (-2252 3400);
DISPLAY INVISIBLE (-2252 3400);
FORCEADD TAP..1
(-2250 3350);
FORCEPROP 3 LASTPIN (-2300 3350) SIG_NAME M_H_CPU1_SA_DQ<9>
J 0
(-2290 3360);
DISPLAY 0.659574 (-2290 3360);
PAINT MONO (-2290 3360);
DISPLAY INVISIBLE (-2290 3360);
FORCEPROP 1 LASTPIN (-2300 3350) BN 9
J 0
(-2312 3358);
DISPLAY 0.680851 (-2312 3358);
PAINT GREEN (-2312 3358);
FORCEPROP 2 LAST CDS_LIB standard
J 0
(-2250 3350);
PAINT MONO (-2250 3350);
DISPLAY INVISIBLE (-2250 3350);
FORCEPROP 1 LAST BODY_TYPE PLUMBING
J 0
(-2250 3400);
DISPLAY 0.872340 (-2250 3400);
PAINT GREEN (-2250 3400);
DISPLAY INVISIBLE (-2250 3400);
FORCEPROP 1 LAST HDL_TAP TRUE
J 0
(-1925 3225);
DISPLAY 0.872340 (-1925 3225);
DISPLAY INVISIBLE (-1925 3225);
FORCEPROP 1 LAST PATH I89
J 0
(-2252 3350);
DISPLAY 0.872340 (-2252 3350);
PAINT GREEN (-2252 3350);
DISPLAY INVISIBLE (-2252 3350);
FORCEADD OFFPAGE..2
R 2
(-4825 1000);
FORCEPROP 2 LAST $XR0 58 
J 0
(-5079 1000);
DISPLAY 0.638298 (-5079 1000);
PAINT MONO (-5079 1000);
FORCEPROP 2 LAST CDS_LIB standard
J 0
(-4825 1000);
PAINT MONO (-4825 1000);
DISPLAY INVISIBLE (-4825 1000);
FORCEPROP 1 LAST OFFPAGE TRUE
J 2
(-5150 875);
DISPLAY 0.872340 (-5150 875);
DISPLAY INVISIBLE (-5150 875);
FORCEPROP 1 LAST COMMENT_BODY TRUE
J 2
(-4780 905);
DISPLAY 0.872340 (-4780 905);
PAINT GREEN (-4780 905);
DISPLAY INVISIBLE (-4780 905);
FORCEPROP 2 LAST PATH I9
J 0
(-4775 1075);
DISPLAY 1.021277 (-4775 1075);
DISPLAY INVISIBLE (-4775 1075);
FORCEADD TAP..1
(-2250 3450);
FORCEPROP 3 LASTPIN (-2300 3450) SIG_NAME M_H_CPU1_SA_DQ<11>
J 0
(-2290 3460);
DISPLAY 0.659574 (-2290 3460);
PAINT MONO (-2290 3460);
DISPLAY INVISIBLE (-2290 3460);
FORCEPROP 1 LASTPIN (-2300 3450) BN 11
J 0
(-2312 3458);
DISPLAY 0.680851 (-2312 3458);
PAINT GREEN (-2312 3458);
FORCEPROP 2 LAST CDS_LIB standard
J 0
(-2250 3450);
PAINT MONO (-2250 3450);
DISPLAY INVISIBLE (-2250 3450);
FORCEPROP 1 LAST BODY_TYPE PLUMBING
J 0
(-2250 3500);
DISPLAY 0.872340 (-2250 3500);
PAINT GREEN (-2250 3500);
DISPLAY INVISIBLE (-2250 3500);
FORCEPROP 1 LAST HDL_TAP TRUE
J 0
(-1925 3325);
DISPLAY 0.872340 (-1925 3325);
DISPLAY INVISIBLE (-1925 3325);
FORCEPROP 1 LAST PATH I90
J 0
(-2252 3450);
DISPLAY 0.872340 (-2252 3450);
PAINT GREEN (-2252 3450);
DISPLAY INVISIBLE (-2252 3450);
FORCEADD TAP..1
(-2250 3500);
FORCEPROP 3 LASTPIN (-2300 3500) SIG_NAME M_H_CPU1_SA_DQ<12>
J 0
(-2290 3510);
DISPLAY 0.659574 (-2290 3510);
PAINT MONO (-2290 3510);
DISPLAY INVISIBLE (-2290 3510);
FORCEPROP 1 LASTPIN (-2300 3500) BN 12
J 0
(-2312 3508);
DISPLAY 0.680851 (-2312 3508);
PAINT GREEN (-2312 3508);
FORCEPROP 2 LAST CDS_LIB standard
J 0
(-2250 3500);
PAINT MONO (-2250 3500);
DISPLAY INVISIBLE (-2250 3500);
FORCEPROP 1 LAST BODY_TYPE PLUMBING
J 0
(-2250 3550);
DISPLAY 0.872340 (-2250 3550);
PAINT GREEN (-2250 3550);
DISPLAY INVISIBLE (-2250 3550);
FORCEPROP 1 LAST HDL_TAP TRUE
J 0
(-1925 3375);
DISPLAY 0.872340 (-1925 3375);
DISPLAY INVISIBLE (-1925 3375);
FORCEPROP 1 LAST PATH I91
J 0
(-2252 3500);
DISPLAY 0.872340 (-2252 3500);
PAINT GREEN (-2252 3500);
DISPLAY INVISIBLE (-2252 3500);
FORCEADD TAP..1
(-2250 3600);
FORCEPROP 3 LASTPIN (-2300 3600) SIG_NAME M_H_CPU1_SA_DQ<14>
J 0
(-2290 3610);
DISPLAY 0.659574 (-2290 3610);
PAINT MONO (-2290 3610);
DISPLAY INVISIBLE (-2290 3610);
FORCEPROP 1 LASTPIN (-2300 3600) BN 14
J 0
(-2312 3608);
DISPLAY 0.680851 (-2312 3608);
PAINT GREEN (-2312 3608);
FORCEPROP 2 LAST CDS_LIB standard
J 0
(-2250 3600);
PAINT MONO (-2250 3600);
DISPLAY INVISIBLE (-2250 3600);
FORCEPROP 1 LAST BODY_TYPE PLUMBING
J 0
(-2250 3650);
DISPLAY 0.872340 (-2250 3650);
PAINT GREEN (-2250 3650);
DISPLAY INVISIBLE (-2250 3650);
FORCEPROP 1 LAST HDL_TAP TRUE
J 0
(-1925 3475);
DISPLAY 0.872340 (-1925 3475);
DISPLAY INVISIBLE (-1925 3475);
FORCEPROP 1 LAST PATH I92
J 0
(-2252 3600);
DISPLAY 0.872340 (-2252 3600);
PAINT GREEN (-2252 3600);
DISPLAY INVISIBLE (-2252 3600);
FORCEADD TAP..1
(-2250 3550);
FORCEPROP 3 LASTPIN (-2300 3550) SIG_NAME M_H_CPU1_SA_DQ<13>
J 0
(-2290 3560);
DISPLAY 0.659574 (-2290 3560);
PAINT MONO (-2290 3560);
DISPLAY INVISIBLE (-2290 3560);
FORCEPROP 1 LASTPIN (-2300 3550) BN 13
J 0
(-2312 3558);
DISPLAY 0.680851 (-2312 3558);
PAINT GREEN (-2312 3558);
FORCEPROP 2 LAST CDS_LIB standard
J 0
(-2250 3550);
PAINT MONO (-2250 3550);
DISPLAY INVISIBLE (-2250 3550);
FORCEPROP 1 LAST BODY_TYPE PLUMBING
J 0
(-2250 3600);
DISPLAY 0.872340 (-2250 3600);
PAINT GREEN (-2250 3600);
DISPLAY INVISIBLE (-2250 3600);
FORCEPROP 1 LAST HDL_TAP TRUE
J 0
(-1925 3425);
DISPLAY 0.872340 (-1925 3425);
DISPLAY INVISIBLE (-1925 3425);
FORCEPROP 1 LAST PATH I93
J 0
(-2252 3550);
DISPLAY 0.872340 (-2252 3550);
PAINT GREEN (-2252 3550);
DISPLAY INVISIBLE (-2252 3550);
FORCEADD TAP..1
(-2250 3800);
FORCEPROP 3 LASTPIN (-2300 3800) SIG_NAME M_H_CPU1_SA_DQ<18>
J 0
(-2290 3810);
DISPLAY 0.659574 (-2290 3810);
PAINT MONO (-2290 3810);
DISPLAY INVISIBLE (-2290 3810);
FORCEPROP 1 LASTPIN (-2300 3800) BN 18
J 0
(-2312 3808);
DISPLAY 0.680851 (-2312 3808);
PAINT GREEN (-2312 3808);
FORCEPROP 2 LAST CDS_LIB standard
J 0
(-2250 3800);
PAINT MONO (-2250 3800);
DISPLAY INVISIBLE (-2250 3800);
FORCEPROP 1 LAST BODY_TYPE PLUMBING
J 0
(-2250 3850);
DISPLAY 0.872340 (-2250 3850);
PAINT GREEN (-2250 3850);
DISPLAY INVISIBLE (-2250 3850);
FORCEPROP 1 LAST HDL_TAP TRUE
J 0
(-1925 3675);
DISPLAY 0.872340 (-1925 3675);
DISPLAY INVISIBLE (-1925 3675);
FORCEPROP 1 LAST PATH I94
J 0
(-2252 3800);
DISPLAY 0.872340 (-2252 3800);
PAINT GREEN (-2252 3800);
DISPLAY INVISIBLE (-2252 3800);
FORCEADD TAP..1
(-2250 3750);
FORCEPROP 3 LASTPIN (-2300 3750) SIG_NAME M_H_CPU1_SA_DQ<17>
J 0
(-2290 3760);
DISPLAY 0.659574 (-2290 3760);
PAINT MONO (-2290 3760);
DISPLAY INVISIBLE (-2290 3760);
FORCEPROP 1 LASTPIN (-2300 3750) BN 17
J 0
(-2312 3758);
DISPLAY 0.680851 (-2312 3758);
PAINT GREEN (-2312 3758);
FORCEPROP 2 LAST CDS_LIB standard
J 0
(-2250 3750);
PAINT MONO (-2250 3750);
DISPLAY INVISIBLE (-2250 3750);
FORCEPROP 1 LAST BODY_TYPE PLUMBING
J 0
(-2250 3800);
DISPLAY 0.872340 (-2250 3800);
PAINT GREEN (-2250 3800);
DISPLAY INVISIBLE (-2250 3800);
FORCEPROP 1 LAST HDL_TAP TRUE
J 0
(-1925 3625);
DISPLAY 0.872340 (-1925 3625);
DISPLAY INVISIBLE (-1925 3625);
FORCEPROP 1 LAST PATH I95
J 0
(-2252 3750);
DISPLAY 0.872340 (-2252 3750);
PAINT GREEN (-2252 3750);
DISPLAY INVISIBLE (-2252 3750);
FORCEADD TAP..1
(-2250 3850);
FORCEPROP 3 LASTPIN (-2300 3850) SIG_NAME M_H_CPU1_SA_DQ<19>
J 0
(-2290 3860);
DISPLAY 0.659574 (-2290 3860);
PAINT MONO (-2290 3860);
DISPLAY INVISIBLE (-2290 3860);
FORCEPROP 1 LASTPIN (-2300 3850) BN 19
J 0
(-2312 3858);
DISPLAY 0.680851 (-2312 3858);
PAINT GREEN (-2312 3858);
FORCEPROP 2 LAST CDS_LIB standard
J 0
(-2250 3850);
PAINT MONO (-2250 3850);
DISPLAY INVISIBLE (-2250 3850);
FORCEPROP 1 LAST BODY_TYPE PLUMBING
J 0
(-2250 3900);
DISPLAY 0.872340 (-2250 3900);
PAINT GREEN (-2250 3900);
DISPLAY INVISIBLE (-2250 3900);
FORCEPROP 1 LAST HDL_TAP TRUE
J 0
(-1925 3725);
DISPLAY 0.872340 (-1925 3725);
DISPLAY INVISIBLE (-1925 3725);
FORCEPROP 1 LAST PATH I96
J 0
(-2252 3850);
DISPLAY 0.872340 (-2252 3850);
PAINT GREEN (-2252 3850);
DISPLAY INVISIBLE (-2252 3850);
FORCEADD TAP..1
(-2250 3700);
FORCEPROP 3 LASTPIN (-2300 3700) SIG_NAME M_H_CPU1_SA_DQ<16>
J 0
(-2290 3710);
DISPLAY 0.659574 (-2290 3710);
PAINT MONO (-2290 3710);
DISPLAY INVISIBLE (-2290 3710);
FORCEPROP 1 LASTPIN (-2300 3700) BN 16
J 0
(-2312 3708);
DISPLAY 0.680851 (-2312 3708);
PAINT GREEN (-2312 3708);
FORCEPROP 2 LAST CDS_LIB standard
J 0
(-2250 3700);
PAINT MONO (-2250 3700);
DISPLAY INVISIBLE (-2250 3700);
FORCEPROP 1 LAST BODY_TYPE PLUMBING
J 0
(-2250 3750);
DISPLAY 0.872340 (-2250 3750);
PAINT GREEN (-2250 3750);
DISPLAY INVISIBLE (-2250 3750);
FORCEPROP 1 LAST HDL_TAP TRUE
J 0
(-1925 3575);
DISPLAY 0.872340 (-1925 3575);
DISPLAY INVISIBLE (-1925 3575);
FORCEPROP 1 LAST PATH I97
J 0
(-2252 3700);
DISPLAY 0.872340 (-2252 3700);
PAINT GREEN (-2252 3700);
DISPLAY INVISIBLE (-2252 3700);
FORCEADD TAP..1
(-2250 3650);
FORCEPROP 3 LASTPIN (-2300 3650) SIG_NAME M_H_CPU1_SA_DQ<15>
J 0
(-2290 3660);
DISPLAY 0.659574 (-2290 3660);
PAINT MONO (-2290 3660);
DISPLAY INVISIBLE (-2290 3660);
FORCEPROP 1 LASTPIN (-2300 3650) BN 15
J 0
(-2312 3658);
DISPLAY 0.680851 (-2312 3658);
PAINT GREEN (-2312 3658);
FORCEPROP 2 LAST CDS_LIB standard
J 0
(-2250 3650);
PAINT MONO (-2250 3650);
DISPLAY INVISIBLE (-2250 3650);
FORCEPROP 1 LAST BODY_TYPE PLUMBING
J 0
(-2250 3700);
DISPLAY 0.872340 (-2250 3700);
PAINT GREEN (-2250 3700);
DISPLAY INVISIBLE (-2250 3700);
FORCEPROP 1 LAST HDL_TAP TRUE
J 0
(-1925 3525);
DISPLAY 0.872340 (-1925 3525);
DISPLAY INVISIBLE (-1925 3525);
FORCEPROP 1 LAST PATH I98
J 0
(-2252 3650);
DISPLAY 0.872340 (-2252 3650);
PAINT GREEN (-2252 3650);
DISPLAY INVISIBLE (-2252 3650);
FORCEADD TAP..1
(-2250 3950);
FORCEPROP 3 LASTPIN (-2300 3950) SIG_NAME M_H_CPU1_SA_DQ<21>
J 0
(-2290 3960);
DISPLAY 0.659574 (-2290 3960);
PAINT MONO (-2290 3960);
DISPLAY INVISIBLE (-2290 3960);
FORCEPROP 1 LASTPIN (-2300 3950) BN 21
J 0
(-2312 3958);
DISPLAY 0.680851 (-2312 3958);
PAINT GREEN (-2312 3958);
FORCEPROP 2 LAST CDS_LIB standard
J 0
(-2250 3950);
PAINT MONO (-2250 3950);
DISPLAY INVISIBLE (-2250 3950);
FORCEPROP 1 LAST BODY_TYPE PLUMBING
J 0
(-2250 4000);
DISPLAY 0.872340 (-2250 4000);
PAINT GREEN (-2250 4000);
DISPLAY INVISIBLE (-2250 4000);
FORCEPROP 1 LAST HDL_TAP TRUE
J 0
(-1925 3825);
DISPLAY 0.872340 (-1925 3825);
DISPLAY INVISIBLE (-1925 3825);
FORCEPROP 1 LAST PATH I99
J 0
(-2252 3950);
DISPLAY 0.872340 (-2252 3950);
PAINT GREEN (-2252 3950);
DISPLAY INVISIBLE (-2252 3950);
FORCEADD CAD_NOTE..1
(-400 0);
FORCEPROP 0 LAST S1 PLACE THE BYPASS CAPS CLOSE TO DIMM
J 0
(-525 -125);
DISPLAY 1.021277 (-525 -125);
PAINT WHITE (-525 -125);
FORCEPROP 2 LAST CDS_LIB logical_power
J 0
(-400 0);
PAINT MONO (-400 0);
DISPLAY INVISIBLE (-400 0);
FORCEPROP 1 LAST COMMENT_BODY TRUE
J 0
(-375 100);
DISPLAY 0.978723 (-375 100);
DISPLAY INVISIBLE (-375 100);
FORCEADD QUANTA_TITLE_BLOCK_C..1
(4050 -1300);
FORCEPROP 0 LAST CDS_CON_LAST_MODIFIED Fri Aug 25 14:01:34 2023
J 0
(2165 -1285);
PAINT MONO (2165 -1285);
DISPLAY INVISIBLE (2165 -1285);
FORCEPROP 1 LAST CUSTOM_TXT_CDS <CON_LAST_MODIFIED>
J 0
(2165 -1285);
DISPLAY 0.978723 (2165 -1285);
FORCEPROP 2 LAST CUSTOM_TXT_CDS <XR_PAGE_TITLE>
J 0
(-3840 3950);
DISPLAY 0.638298 (-3840 3950);
PAINT PINK (-3840 3950);
DISPLAY INVISIBLE (-3840 3950);
FORCEPROP 2 LAST CUSTOM_TXT_CDS <Q_NUMBER>
J 0
(2647 -1197);
DISPLAY 1.212766 (2647 -1197);
FORCEPROP 1 LAST CUSTOM_TXT_CDS <NAME_2>
J 0
(875 -1250);
FORCEPROP 1 LAST CUSTOM_TXT_CDS <NAME_1>
J 0
(875 -1125);
FORCEPROP 1 LAST CUSTOM_TXT_CDS <Q_PROJ>
J 0
(1668 -1198);
DISPLAY 1.212766 (1668 -1198);
FORCEPROP 1 LAST CUSTOM_TXT_CDS <Q_REV>
J 0
(3866 -1197);
DISPLAY 1.212766 (3866 -1197);
FORCEPROP 1 LAST CUSTOM_TXT_CDS <CON_PAGE_NUM> OF <CON_TOTAL_PAGES>
J 0
(3604 -1282);
DISPLAY 0.978723 (3604 -1282);
FORCEPROP 1 LAST Q_TITLE DDR5 - CPU1 CHH DIMM2(BLACK)
J 0
(-5316 -1274);
DISPLAY 2.446809 (-5316 -1274);
PAINT GREEN (-5316 -1274);
FORCEPROP 1 LAST Q_DEPT 
J 1
(287 -1251);
DISPLAY 1.957447 (287 -1251);
PAINT GREEN (287 -1251);
FORCEPROP 2 LAST CDS_XR_PAGE_TITLE CR-113 : @S9S_MB_2U_LIB.S9S_MB_2U(SCH_1):PAGE113
J 0
(-3840 3950);
DISPLAY 0.638298 (-3840 3950);
PAINT PINK (-3840 3950);
DISPLAY INVISIBLE (-3840 3950);
FORCEPROP 1 LAST COMMENT_BODY TRUE
J 0
(4062 -1313);
DISPLAY 0.978723 (4062 -1313);
PAINT GREEN (4062 -1313);
DISPLAY INVISIBLE (4062 -1313);
FORCEPROP 2 LAST CDS_LIB pure_quanta
J 0
(4050 -1300);
PAINT MONO (4050 -1300);
DISPLAY INVISIBLE (4050 -1300);
FORCEPROP 1 LAST CDS_LMAN_SYM_OUTLINE -9475,6775,100,-125
J 0
(4050 -1300);
DISPLAY 0.468085 (4050 -1300);
PAINT GREEN (4050 -1300);
DISPLAY INVISIBLE (4050 -1300);
FORCEPROP 2 LAST PAGE_BORDER TRUE
J 0
(-3840 3950);
DISPLAY 0.638298 (-3840 3950);
PAINT PINK (-3840 3950);
DISPLAY INVISIBLE (-3840 3950);
WIRE 17 -1 (-2200 4425)(-2200 4475);
WIRE 17 -1 (-2200 4375)(-2200 4425);
WIRE 17 -1 (-2200 4475)(-1475 4475);
FORCEPROP 2 LAST SIG_NAME M_H_CPU1_SA_DQ<31:0>
J 0
(-2135 4485);
DISPLAY 0.680851 (-2135 4485);
PAINT WHITE (-2135 4485);
WIRE 17 -1 (-3950 2875)(-3950 2925);
WIRE 17 -1 (-3950 2825)(-3950 2875);
WIRE 17 -1 (-3950 2925)(-3950 2975);
WIRE 17 -1 (-3950 2975)(-3950 3025);
WIRE 17 -1 (-3950 2775)(-3950 2825);
WIRE 17 -1 (-3950 2725)(-3950 2775);
WIRE 17 -1 (-3950 3025)(-3950 3075);
WIRE 17 -1 (-4775 3075)(-3950 3075);
FORCEPROP 2 LAST SIG_NAME M_H_CPU1_SA_CB<7:0>
J 0
(-4685 3085);
DISPLAY 0.680851 (-4685 3085);
PAINT WHITE (-4685 3085);
WIRE 17 -1 (-3950 2575)(-3950 2625);
WIRE 17 -1 (-3950 2525)(-3950 2575);
WIRE 17 -1 (-4775 2625)(-3950 2625);
FORCEPROP 2 LAST SIG_NAME M_H_CPU1_SB_CB<7:0>
J 0
(-4685 2635);
DISPLAY 0.680851 (-4685 2635);
PAINT WHITE (-4685 2635);
WIRE 17 -1 (-3950 4175)(-3950 4225);
WIRE 17 -1 (-3950 4225)(-3950 4275);
WIRE 17 -1 (-3950 4275)(-3950 4325);
WIRE 17 -1 (-3950 4325)(-3950 4375);
WIRE 17 -1 (-3950 4375)(-3950 4425);
WIRE 17 -1 (-3950 4425)(-3950 4475);
WIRE 17 -1 (-4775 4475)(-3950 4475);
FORCEPROP 2 LAST SIG_NAME M_H_CPU1_SA_CA<6:0>
J 0
(-4685 4485);
DISPLAY 0.680851 (-4685 4485);
PAINT WHITE (-4685 4485);
WIRE 17 -1 (-3950 3775)(-3950 3825);
WIRE 17 -1 (-3950 3825)(-3950 3875);
WIRE 17 -1 (-3950 3875)(-3950 3925);
WIRE 17 -1 (-3950 3925)(-3950 3975);
WIRE 17 -1 (-3950 3975)(-3950 4025);
WIRE 17 -1 (-3950 4025)(-3950 4075);
WIRE 17 -1 (-4775 4075)(-3950 4075);
FORCEPROP 2 LAST SIG_NAME M_H_CPU1_SB_CA<6:0>
J 0
(-4685 4085);
DISPLAY 0.680851 (-4685 4085);
PAINT WHITE (-4685 4085);
WIRE 17 -1 (-3950 2375)(-3950 2425);
WIRE 17 -1 (-3950 2325)(-3950 2375);
WIRE 17 -1 (-3950 2425)(-3950 2475);
WIRE 17 -1 (-3950 2475)(-3950 2525);
WIRE 17 -1 (-3950 2275)(-3950 2325);
WIRE 17 -1 (-2200 4325)(-2200 4375);
WIRE 17 -1 (-2200 4275)(-2200 4325);
WIRE 17 -1 (-2200 4225)(-2200 4275);
WIRE 17 -1 (-2200 4175)(-2200 4225);
WIRE 17 -1 (-2200 4125)(-2200 4175);
WIRE 17 -1 (-2200 4075)(-2200 4125);
WIRE 17 -1 (-2200 4025)(-2200 4075);
WIRE 17 -1 (-2200 3975)(-2200 4025);
WIRE 17 -1 (-2200 3925)(-2200 3975);
WIRE 17 -1 (-2200 3875)(-2200 3925);
WIRE 17 -1 (-2200 3825)(-2200 3875);
WIRE 17 -1 (-2200 3775)(-2200 3825);
WIRE 17 -1 (-2200 3725)(-2200 3775);
WIRE 17 -1 (-2200 3675)(-2200 3725);
WIRE 17 -1 (-2200 3625)(-2200 3675);
WIRE 17 -1 (-2200 3575)(-2200 3625);
WIRE 17 -1 (-2200 3525)(-2200 3575);
WIRE 17 -1 (-2200 3475)(-2200 3525);
WIRE 17 -1 (-2200 3425)(-2200 3475);
WIRE 17 -1 (-2200 3375)(-2200 3425);
WIRE 17 -1 (-2200 3325)(-2200 3375);
WIRE 17 -1 (-2200 3275)(-2200 3325);
WIRE 17 -1 (-2200 3225)(-2200 3275);
WIRE 17 -1 (-2200 3175)(-2200 3225);
WIRE 17 -1 (-2200 3125)(-2200 3175);
WIRE 17 -1 (-2200 3075)(-2200 3125);
WIRE 17 -1 (-2200 3025)(-2200 3075);
WIRE 17 -1 (-2200 2975)(-2200 3025);
WIRE 17 -1 (-2200 2925)(-2200 2975);
WIRE 17 -1 (-2200 2775)(-2200 2825);
WIRE 17 -1 (-2200 2725)(-2200 2775);
WIRE 17 -1 (-2200 2825)(-1475 2825);
FORCEPROP 2 LAST SIG_NAME M_H_CPU1_SB_DQ<31:0>
J 0
(-2135 2835);
DISPLAY 0.680851 (-2135 2835);
PAINT WHITE (-2135 2835);
WIRE 17 -1 (-2200 2675)(-2200 2725);
WIRE 17 -1 (-2200 2525)(-2200 2575);
WIRE 17 -1 (-2200 2475)(-2200 2525);
WIRE 17 -1 (-2200 2575)(-2200 2625);
WIRE 17 -1 (-2200 2625)(-2200 2675);
WIRE 17 -1 (-2200 2425)(-2200 2475);
WIRE 17 -1 (-2200 2375)(-2200 2425);
WIRE 17 -1 (-2200 2325)(-2200 2375);
WIRE 17 -1 (-2200 2275)(-2200 2325);
WIRE 17 -1 (-2200 2225)(-2200 2275);
WIRE 17 -1 (-2200 2175)(-2200 2225);
WIRE 17 -1 (-2200 2125)(-2200 2175);
WIRE 17 -1 (-2200 2075)(-2200 2125);
WIRE 17 -1 (-2200 2025)(-2200 2075);
WIRE 17 -1 (-2200 1975)(-2200 2025);
WIRE 17 -1 (-2200 1925)(-2200 1975);
WIRE 17 -1 (-2200 1875)(-2200 1925);
WIRE 17 -1 (-2200 1825)(-2200 1875);
WIRE 17 -1 (-2200 1775)(-2200 1825);
WIRE 17 -1 (-2200 1725)(-2200 1775);
WIRE 17 -1 (-2200 1675)(-2200 1725);
WIRE 17 -1 (-2200 1625)(-2200 1675);
WIRE 17 -1 (-2200 1575)(-2200 1625);
WIRE 17 -1 (-2200 1525)(-2200 1575);
WIRE 17 -1 (-2200 1475)(-2200 1525);
WIRE 17 -1 (-2200 1425)(-2200 1475);
WIRE 17 -1 (-2200 1375)(-2200 1425);
WIRE 17 -1 (-2200 1325)(-2200 1375);
WIRE 17 -1 (-2200 1275)(-2200 1325);
WIRE 17 -1 (550 2525)(550 2625);
WIRE 17 -1 (550 2625)(550 2725);
WIRE 17 -1 (550 2725)(550 2825);
WIRE 17 -1 (550 2925)(550 2825);
WIRE 17 -1 (550 2925)(550 3025);
WIRE 17 -1 (550 3025)(550 3125);
WIRE 17 -1 (550 3125)(550 3225);
WIRE 17 -1 (550 3225)(550 3325);
WIRE 17 -1 (550 3325)(550 3425);
WIRE 17 -1 (550 3425)(1575 3425);
FORCEPROP 2 LAST SIG_NAME M_H_CPU1_SB_DQS_DP<9:0>
J 0
(790 3435);
DISPLAY 0.680851 (790 3435);
PAINT WHITE (790 3435);
WIRE 17 -1 (550 3575)(550 3675);
WIRE 17 -1 (550 3675)(550 3775);
WIRE 17 -1 (550 3775)(550 3875);
WIRE 17 -1 (550 3975)(550 3875);
WIRE 17 -1 (550 3975)(550 4075);
WIRE 17 -1 (550 4075)(550 4175);
WIRE 17 -1 (550 4175)(550 4275);
WIRE 17 -1 (550 4275)(550 4375);
WIRE 17 -1 (550 4375)(550 4475);
WIRE 17 -1 (550 4475)(1575 4475);
FORCEPROP 2 LAST SIG_NAME M_H_CPU1_SA_DQS_DP<9:0>
J 0
(790 4485);
DISPLAY 0.680851 (790 4485);
PAINT WHITE (790 4485);
WIRE 17 -1 (725 2575)(725 2675);
WIRE 17 -1 (725 2475)(725 2575);
WIRE 17 -1 (725 2675)(725 2775);
WIRE 17 -1 (725 2875)(725 2775);
WIRE 17 -1 (725 2875)(725 2975);
WIRE 17 -1 (725 2975)(725 3075);
WIRE 17 -1 (725 3075)(725 3175);
WIRE 17 -1 (725 3175)(725 3275);
WIRE 17 -1 (725 3275)(725 3375);
WIRE 17 -1 (725 3375)(1575 3375);
FORCEPROP 2 LAST SIG_NAME M_H_CPU1_SB_DQS_DN<9:0>
J 0
(790 3385);
DISPLAY 0.680851 (790 3385);
PAINT WHITE (790 3385);
WIRE 17 -1 (725 3525)(725 3625);
WIRE 17 -1 (725 3625)(725 3725);
WIRE 17 -1 (725 3725)(725 3825);
WIRE 17 -1 (725 3925)(725 3825);
WIRE 17 -1 (725 3925)(725 4025);
WIRE 17 -1 (725 4025)(725 4125);
WIRE 17 -1 (725 4125)(725 4225);
WIRE 17 -1 (725 4225)(725 4325);
WIRE 17 -1 (725 4325)(725 4425);
WIRE 17 -1 (725 4425)(1575 4425);
FORCEPROP 2 LAST SIG_NAME M_H_CPU1_SA_DQS_DN<9:0>
J 0
(790 4435);
DISPLAY 0.680851 (790 4435);
PAINT WHITE (790 4435);
WIRE 16 -1 (2175 4950)(2175 4450);
WIRE 16 -1 (475 850)(475 800);
WIRE 16 -1 (-525 675)(-525 850);
WIRE 16 -1 (-4725 2275)(-4725 2000);
WIRE 16 -1 (3875 1100)(3875 800);
WIRE 16 -1 (3875 1150)(3875 1100);
WIRE 16 -1 (3625 1100)(3875 1100);
WIRE 16 -1 (2175 800)(2175 1200);
WIRE 16 -1 (1100 250)(1100 325);
WIRE 16 -1 (-525 475)(-525 250);
WIRE 16 -1 (-3675 125)(-3675 200);
WIRE 16 3135 (1725 1075)(-875 1075);
WIRE 16 3135 (1725 -225)(1725 1075);
WIRE 16 3135 (-875 1075)(-875 -225);
WIRE 16 3135 (-875 -225)(1725 -225);
WIRE 16 -1 (475 325)(475 475);
WIRE 16 -1 (1100 325)(475 325);
WIRE 16 -1 (1100 325)(1100 475);
WIRE 16 -1 (-3675 1900)(-4675 1900);
FORCEPROP 2 LAST SIG_NAME I3C_SPD_DDREFGH_CPU1_LVC1_SDA
J 0
(-4685 1910);
DISPLAY 0.680851 (-4685 1910);
PAINT WHITE (-4685 1910);
WIRE 16 -1 (-5150 1750)(-5000 1750);
WIRE 16 -1 (-5150 1750)(-5150 1850);
WIRE 16 -1 (-3675 1850)(-5150 1850);
FORCEPROP 2 LAST SIG_NAME I3C_SPD_DDREFGH_CPU1_LVC1_SCL_R8
J 0
(-4735 1860);
DISPLAY 0.680851 (-4735 1860);
PAINT WHITE (-4735 1860);
WIRE 16 -1 (-4000 2150)(-3675 2150);
WIRE 16 -1 (-4000 2200)(-4775 2200);
FORCEPROP 2 LAST SIG_NAME RST_M_GH_CPU1_FPGA_N
J 0
(-4687 2209);
DISPLAY 0.680851 (-4687 2209);
PAINT WHITE (-4687 2209);
WIRE 16 -1 (-4000 2200)(-4000 2150);
WIRE 16 -1 (-3675 2100)(-4775 2100);
FORCEPROP 2 LAST SIG_NAME M_H_CPU1_ALERT_N
J 0
(-4687 2109);
DISPLAY 0.680851 (-4687 2109);
PAINT WHITE (-4687 2109);
WIRE 16 -1 (-4725 2000)(-3675 2000);
WIRE 16 -1 (-3550 1675)(-3600 1675);
WIRE 16 -1 (-4800 1750)(-3550 1750);
FORCEPROP 2 LAST SIG_NAME I3C_SPD_DDREFGH_CPU1_LVC1_SCL
J 0
(-4685 1760);
DISPLAY 0.680851 (-4685 1760);
PAINT WHITE (-4685 1760);
WIRE 16 -1 (-3550 1750)(-3550 1675);
WIRE 16 -1 (-3675 1400)(-4775 1400);
FORCEPROP 2 LAST SIG_NAME TP_CHH_CPU1_DIMM2_FRU_4
J 0
(-4687 1409);
DISPLAY 0.680851 (-4687 1409);
PAINT WHITE (-4687 1409);
WIRE 16 -1 (-3675 1350)(-4775 1350);
FORCEPROP 2 LAST SIG_NAME TP_CHH_CPU1_DIMM2_FRU_3
J 0
(-4687 1359);
DISPLAY 0.680851 (-4687 1359);
PAINT WHITE (-4687 1359);
WIRE 16 -1 (-3675 1450)(-4775 1450);
FORCEPROP 2 LAST SIG_NAME TP_CHH_CPU1_DIMM2_FRU_5
J 0
(-4687 1459);
DISPLAY 0.680851 (-4687 1459);
PAINT WHITE (-4687 1459);
WIRE 16 -1 (-3675 1500)(-4775 1500);
FORCEPROP 2 LAST SIG_NAME TP_CHH_CPU1_DIMM2_FRU_6
J 0
(-4687 1509);
DISPLAY 0.680851 (-4687 1509);
PAINT WHITE (-4687 1509);
WIRE 16 -1 (-3675 1600)(-4775 1600);
FORCEPROP 2 LAST SIG_NAME PWRGD_CHH_CPU1_DIMM2
J 0
(-4687 1609);
DISPLAY 0.680851 (-4687 1609);
PAINT WHITE (-4687 1609);
WIRE 16 -1 (-3675 1950)(-4675 1950);
FORCEPROP 2 LAST SIG_NAME PD_CHH_CPU1_DIMM2_SAA
J 0
(-4685 1960);
DISPLAY 0.680851 (-4685 1960);
PAINT WHITE (-4685 1960);
WIRE 16 -1 (-2475 2650)(-2300 2650);
WIRE 16 -1 (-2475 2950)(-2300 2950);
WIRE 16 -1 (-3850 2950)(-3675 2950);
WIRE 16 -1 (-3675 1300)(-4775 1300);
FORCEPROP 2 LAST SIG_NAME TP_CHH_CPU1_DIMM2_FRU_2
J 0
(-4687 1309);
DISPLAY 0.680851 (-4687 1309);
PAINT WHITE (-4687 1309);
WIRE 16 -1 (-3850 2550)(-3675 2550);
WIRE 16 -1 (-3850 2700)(-3675 2700);
WIRE 16 -1 (475 800)(475 675);
WIRE 16 -1 (1100 800)(475 800);
WIRE 16 -1 (1100 675)(1100 800);
WIRE 16 -1 (2175 1200)(2425 1200);
WIRE 16 -1 (2175 1200)(2175 1250);
WIRE 16 -1 (2175 1250)(2425 1250);
WIRE 16 -1 (2175 1250)(2175 1300);
WIRE 16 -1 (2175 1300)(2425 1300);
WIRE 16 -1 (2175 1300)(2175 1350);
WIRE 16 -1 (2175 1350)(2425 1350);
WIRE 16 -1 (2175 1350)(2175 1400);
WIRE 16 -1 (2175 1400)(2425 1400);
WIRE 16 -1 (2175 1400)(2175 1450);
WIRE 16 -1 (2175 1450)(2425 1450);
WIRE 16 -1 (2175 1450)(2175 1500);
WIRE 16 -1 (2175 1500)(2425 1500);
WIRE 16 -1 (2175 1500)(2175 1550);
WIRE 16 -1 (2175 1550)(2425 1550);
WIRE 16 -1 (2175 1550)(2175 1600);
WIRE 16 -1 (2175 1600)(2425 1600);
WIRE 16 -1 (2175 1600)(2175 1650);
WIRE 16 -1 (2175 1650)(2425 1650);
WIRE 16 -1 (2175 1650)(2175 1700);
WIRE 16 -1 (2425 1700)(2175 1700);
WIRE 16 -1 (2175 1700)(2175 1750);
WIRE 16 -1 (2175 1750)(2425 1750);
WIRE 16 -1 (2175 1750)(2175 1800);
WIRE 16 -1 (2175 1800)(2425 1800);
WIRE 16 -1 (2175 1800)(2175 1850);
WIRE 16 -1 (2175 1850)(2425 1850);
WIRE 16 -1 (2175 1850)(2175 1900);
WIRE 16 -1 (2175 1900)(2425 1900);
WIRE 16 -1 (2175 1900)(2175 1950);
WIRE 16 -1 (2175 1950)(2425 1950);
WIRE 16 -1 (2175 1950)(2175 2000);
WIRE 16 -1 (2175 2000)(2425 2000);
WIRE 16 -1 (2175 2000)(2175 2050);
WIRE 16 -1 (2175 2050)(2425 2050);
WIRE 16 -1 (2175 2050)(2175 2100);
WIRE 16 -1 (2175 2100)(2425 2100);
WIRE 16 -1 (2175 2100)(2175 2150);
WIRE 16 -1 (2175 2150)(2425 2150);
WIRE 16 -1 (2175 2150)(2175 2200);
WIRE 16 -1 (2425 2200)(2175 2200);
WIRE 16 -1 (2175 2200)(2175 2250);
WIRE 16 -1 (2175 2250)(2425 2250);
WIRE 16 -1 (2175 2250)(2175 2300);
WIRE 16 -1 (2175 2300)(2425 2300);
WIRE 16 -1 (2175 2300)(2175 2350);
WIRE 16 -1 (2175 2350)(2425 2350);
WIRE 16 -1 (2175 2350)(2175 2400);
WIRE 16 -1 (2175 2400)(2425 2400);
WIRE 16 -1 (2175 2400)(2175 2450);
WIRE 16 -1 (2175 2450)(2425 2450);
WIRE 16 -1 (2175 2450)(2175 2500);
WIRE 16 -1 (2175 2500)(2425 2500);
WIRE 16 -1 (2175 2500)(2175 2550);
WIRE 16 -1 (2175 2550)(2425 2550);
WIRE 16 -1 (2175 2550)(2175 2600);
WIRE 16 -1 (2175 2600)(2425 2600);
WIRE 16 -1 (2175 2600)(2175 2650);
WIRE 16 -1 (2175 2650)(2425 2650);
WIRE 16 -1 (2175 2650)(2175 2700);
WIRE 16 -1 (2425 2700)(2175 2700);
WIRE 16 -1 (2175 2700)(2175 2750);
WIRE 16 -1 (2175 2750)(2425 2750);
WIRE 16 -1 (2175 2750)(2175 2800);
WIRE 16 -1 (2175 2800)(2425 2800);
WIRE 16 -1 (2175 2800)(2175 2850);
WIRE 16 -1 (2175 2850)(2425 2850);
WIRE 16 -1 (2175 2850)(2175 2900);
WIRE 16 -1 (2175 2900)(2425 2900);
WIRE 16 -1 (2175 2900)(2175 2950);
WIRE 16 -1 (2175 2950)(2425 2950);
WIRE 16 -1 (2175 2950)(2175 3000);
WIRE 16 -1 (2175 3000)(2425 3000);
WIRE 16 -1 (2175 3000)(2175 3050);
WIRE 16 -1 (2175 3050)(2425 3050);
WIRE 16 -1 (2175 3050)(2175 3100);
WIRE 16 -1 (2175 3100)(2425 3100);
WIRE 16 -1 (2175 3100)(2175 3150);
WIRE 16 -1 (2175 3150)(2425 3150);
WIRE 16 -1 (2175 3150)(2175 3200);
WIRE 16 -1 (2425 3200)(2175 3200);
WIRE 16 -1 (2175 3200)(2175 3250);
WIRE 16 -1 (2175 3250)(2425 3250);
WIRE 16 -1 (2175 3250)(2175 3300);
WIRE 16 -1 (2175 3300)(2425 3300);
WIRE 16 -1 (2175 3300)(2175 3350);
WIRE 16 -1 (2175 3350)(2425 3350);
WIRE 16 -1 (2175 3350)(2175 3400);
WIRE 16 -1 (2175 3400)(2425 3400);
WIRE 16 -1 (2175 3400)(2175 3450);
WIRE 16 -1 (2175 3450)(2425 3450);
WIRE 16 -1 (2175 3450)(2175 3500);
WIRE 16 -1 (2175 3500)(2425 3500);
WIRE 16 -1 (2175 3500)(2175 3550);
WIRE 16 -1 (2175 3550)(2425 3550);
WIRE 16 -1 (2175 3550)(2175 3600);
WIRE 16 -1 (2175 3600)(2425 3600);
WIRE 16 -1 (2175 3600)(2175 3650);
WIRE 16 -1 (2175 3650)(2425 3650);
WIRE 16 -1 (2175 3650)(2175 3700);
WIRE 16 -1 (2425 3700)(2175 3700);
WIRE 16 -1 (2175 3700)(2175 3750);
WIRE 16 -1 (2175 3750)(2425 3750);
WIRE 16 -1 (2175 3750)(2175 3800);
WIRE 16 -1 (2175 3800)(2425 3800);
WIRE 16 -1 (2175 3800)(2175 3850);
WIRE 16 -1 (2175 3850)(2425 3850);
WIRE 16 -1 (2175 3850)(2175 3900);
WIRE 16 -1 (2175 3900)(2425 3900);
WIRE 16 -1 (2175 3900)(2175 3950);
WIRE 16 -1 (2175 3950)(2425 3950);
WIRE 16 -1 (2175 3950)(2175 4000);
WIRE 16 -1 (2175 4000)(2425 4000);
WIRE 16 -1 (2175 4000)(2175 4050);
WIRE 16 -1 (2175 4050)(2425 4050);
WIRE 16 -1 (2175 4050)(2175 4100);
WIRE 16 -1 (2175 4100)(2425 4100);
WIRE 16 -1 (2175 4100)(2175 4150);
WIRE 16 -1 (2175 4150)(2425 4150);
WIRE 16 -1 (2175 4150)(2175 4200);
WIRE 16 -1 (2425 4200)(2175 4200);
WIRE 16 -1 (2175 4200)(2175 4250);
WIRE 16 -1 (2175 4250)(2425 4250);
WIRE 16 -1 (2175 4250)(2175 4300);
WIRE 16 -1 (2425 4300)(2175 4300);
WIRE 16 -1 (2425 4450)(2175 4450);
WIRE 16 -1 (2175 4450)(2175 4400);
WIRE 16 -1 (2175 4400)(2425 4400);
WIRE 16 -1 (2175 4400)(2175 4350);
WIRE 16 -1 (2425 4350)(2175 4350);
WIRE 16 -1 (3625 1150)(3875 1150);
WIRE 16 -1 (3625 1200)(3875 1200);
WIRE 16 -1 (3875 1200)(3875 1150);
WIRE 16 -1 (3625 1300)(3875 1300);
WIRE 16 -1 (3875 1300)(3875 1200);
WIRE 16 -1 (3625 1350)(3875 1350);
WIRE 16 -1 (3875 1350)(3875 1300);
WIRE 16 -1 (3625 1400)(3875 1400);
WIRE 16 -1 (3875 1350)(3875 1400);
WIRE 16 -1 (3625 1450)(3875 1450);
WIRE 16 -1 (3875 1450)(3875 1400);
WIRE 16 -1 (3625 1500)(3875 1500);
WIRE 16 -1 (3875 1500)(3875 1450);
WIRE 16 -1 (3875 1550)(3875 1500);
WIRE 16 -1 (3625 1550)(3875 1550);
WIRE 16 -1 (3625 1600)(3875 1600);
WIRE 16 -1 (3875 1600)(3875 1550);
WIRE 16 -1 (3625 1650)(3875 1650);
WIRE 16 -1 (3875 1650)(3875 1600);
WIRE 16 -1 (3625 1700)(3875 1700);
WIRE 16 -1 (3875 1700)(3875 1650);
WIRE 16 -1 (3875 1750)(3625 1750);
WIRE 16 -1 (3875 1750)(3875 1700);
WIRE 16 -1 (3875 1800)(3625 1800);
WIRE 16 -1 (3875 1800)(3875 1750);
WIRE 16 -1 (3875 1850)(3625 1850);
WIRE 16 -1 (3875 1850)(3875 1800);
WIRE 16 -1 (3625 1900)(3875 1900);
WIRE 16 -1 (3875 1850)(3875 1900);
WIRE 16 -1 (3875 1950)(3625 1950);
WIRE 16 -1 (3875 1900)(3875 1950);
WIRE 16 -1 (3875 2000)(3625 2000);
WIRE 16 -1 (3875 2000)(3875 1950);
WIRE 16 -1 (3875 2050)(3875 2000);
WIRE 16 -1 (3875 2050)(3625 2050);
WIRE 16 -1 (3875 2100)(3625 2100);
WIRE 16 -1 (3875 2100)(3875 2050);
WIRE 16 -1 (3625 2150)(3875 2150);
WIRE 16 -1 (3875 2150)(3875 2100);
WIRE 16 -1 (3625 2200)(3875 2200);
WIRE 16 -1 (3875 2200)(3875 2150);
WIRE 16 -1 (3625 2250)(3875 2250);
WIRE 16 -1 (3875 2200)(3875 2250);
WIRE 16 -1 (3625 2300)(3875 2300);
WIRE 16 -1 (3875 2300)(3875 2250);
WIRE 16 -1 (3625 2350)(3875 2350);
WIRE 16 -1 (3875 2350)(3875 2300);
WIRE 16 -1 (3625 2400)(3875 2400);
WIRE 16 -1 (3875 2400)(3875 2350);
WIRE 16 -1 (3625 2450)(3875 2450);
WIRE 16 -1 (3875 2450)(3875 2400);
WIRE 16 -1 (3625 2500)(3875 2500);
WIRE 16 -1 (3875 2500)(3875 2450);
WIRE 16 -1 (3875 2550)(3625 2550);
WIRE 16 -1 (3875 2550)(3875 2500);
WIRE 16 -1 (3875 2600)(3875 2550);
WIRE 16 -1 (3875 2600)(3625 2600);
WIRE 16 -1 (3625 2650)(3875 2650);
WIRE 16 -1 (3875 2650)(3875 2600);
WIRE 16 -1 (3625 2700)(3875 2700);
WIRE 16 -1 (3875 2700)(3875 2650);
WIRE 16 -1 (3625 2750)(3875 2750);
WIRE 16 -1 (3875 2700)(3875 2750);
WIRE 16 -1 (3625 2800)(3875 2800);
WIRE 16 -1 (3875 2800)(3875 2750);
WIRE 16 -1 (3625 2850)(3875 2850);
WIRE 16 -1 (3875 2850)(3875 2800);
WIRE 16 -1 (3625 2900)(3875 2900);
WIRE 16 -1 (3875 2900)(3875 2850);
WIRE 16 -1 (3625 2950)(3875 2950);
WIRE 16 -1 (3875 2950)(3875 2900);
WIRE 16 -1 (3625 3000)(3875 3000);
WIRE 16 -1 (3875 3000)(3875 2950);
WIRE 16 -1 (3875 3050)(3625 3050);
WIRE 16 -1 (3875 3050)(3875 3000);
WIRE 16 -1 (3875 3100)(3875 3050);
WIRE 16 -1 (3875 3100)(3625 3100);
WIRE 16 -1 (3625 3150)(3875 3150);
WIRE 16 -1 (3875 3150)(3875 3100);
WIRE 16 -1 (3625 3200)(3875 3200);
WIRE 16 -1 (3875 3200)(3875 3150);
WIRE 16 -1 (3625 3250)(3875 3250);
WIRE 16 -1 (3875 3200)(3875 3250);
WIRE 16 -1 (3625 3300)(3875 3300);
WIRE 16 -1 (3875 3300)(3875 3250);
WIRE 16 -1 (3625 3350)(3875 3350);
WIRE 16 -1 (3875 3350)(3875 3300);
WIRE 16 -1 (3625 3400)(3875 3400);
WIRE 16 -1 (3875 3400)(3875 3350);
WIRE 16 -1 (3625 3450)(3875 3450);
WIRE 16 -1 (3875 3450)(3875 3400);
WIRE 16 -1 (3625 3500)(3875 3500);
WIRE 16 -1 (3875 3500)(3875 3450);
WIRE 16 -1 (3875 3550)(3625 3550);
WIRE 16 -1 (3875 3550)(3875 3500);
WIRE 16 -1 (3875 3600)(3875 3550);
WIRE 16 -1 (3875 3600)(3625 3600);
WIRE 16 -1 (3625 3650)(3875 3650);
WIRE 16 -1 (3875 3650)(3875 3600);
WIRE 16 -1 (3625 3700)(3875 3700);
WIRE 16 -1 (3875 3700)(3875 3650);
WIRE 16 -1 (3625 3750)(3875 3750);
WIRE 16 -1 (3875 3700)(3875 3750);
WIRE 16 -1 (3625 3800)(3875 3800);
WIRE 16 -1 (3875 3800)(3875 3750);
WIRE 16 -1 (3625 3850)(3875 3850);
WIRE 16 -1 (3875 3850)(3875 3800);
WIRE 16 -1 (3625 3900)(3875 3900);
WIRE 16 -1 (3875 3900)(3875 3850);
WIRE 16 -1 (3625 3950)(3875 3950);
WIRE 16 -1 (3875 3950)(3875 3900);
WIRE 16 -1 (3625 4000)(3875 4000);
WIRE 16 -1 (3875 4000)(3875 3950);
WIRE 16 -1 (3625 4050)(3875 4050);
WIRE 16 -1 (3875 4050)(3875 4000);
WIRE 16 -1 (3875 4100)(3875 4050);
WIRE 16 -1 (3625 4100)(3875 4100);
WIRE 16 -1 (3625 4150)(3875 4150);
WIRE 16 -1 (3875 4150)(3875 4100);
WIRE 16 -1 (3625 4200)(3875 4200);
WIRE 16 -1 (3875 4200)(3875 4150);
WIRE 16 -1 (3625 4250)(3875 4250);
WIRE 16 -1 (3875 4250)(3875 4200);
WIRE 16 -1 (3625 4300)(3875 4300);
WIRE 16 -1 (3875 4300)(3875 4250);
WIRE 16 -1 (3625 4350)(3875 4350);
WIRE 16 -1 (3875 4350)(3875 4300);
WIRE 16 -1 (3625 4400)(3875 4400);
WIRE 16 -1 (3875 4400)(3875 4350);
WIRE 16 -1 (3875 4450)(3875 4400);
WIRE 16 -1 (3625 4450)(3875 4450);
WIRE 16 -1 (350 2950)(625 2950);
WIRE 16 -1 (350 4400)(625 4400);
WIRE 16 -1 (350 4300)(625 4300);
WIRE 16 -1 (350 4100)(625 4100);
WIRE 16 -1 (350 4200)(625 4200);
WIRE 16 -1 (350 4000)(625 4000);
WIRE 16 -1 (350 3900)(625 3900);
WIRE 16 -1 (350 3800)(625 3800);
WIRE 16 -1 (350 3600)(625 3600);
WIRE 16 -1 (350 3700)(625 3700);
WIRE 16 -1 (350 3500)(625 3500);
WIRE 16 -1 (350 3350)(625 3350);
WIRE 16 -1 (350 3250)(625 3250);
WIRE 16 -1 (350 3150)(625 3150);
WIRE 16 -1 (350 3050)(625 3050);
WIRE 16 -1 (350 2850)(625 2850);
WIRE 16 -1 (350 2750)(625 2750);
WIRE 16 -1 (350 2650)(625 2650);
WIRE 16 -1 (350 2450)(625 2450);
WIRE 16 -1 (350 2550)(625 2550);
WIRE 16 -1 (350 4450)(450 4450);
WIRE 16 -1 (350 4350)(450 4350);
WIRE 16 -1 (350 4250)(450 4250);
WIRE 16 -1 (350 4150)(450 4150);
WIRE 16 -1 (350 4050)(450 4050);
WIRE 16 -1 (350 3950)(450 3950);
WIRE 16 -1 (350 3850)(450 3850);
WIRE 16 -1 (350 3750)(450 3750);
WIRE 16 -1 (350 3650)(450 3650);
WIRE 16 -1 (350 3550)(450 3550);
WIRE 16 -1 (350 3400)(450 3400);
WIRE 16 -1 (350 3300)(450 3300);
WIRE 16 -1 (350 3200)(450 3200);
WIRE 16 -1 (350 3100)(450 3100);
WIRE 16 -1 (350 3000)(450 3000);
WIRE 16 -1 (350 2900)(450 2900);
WIRE 16 -1 (350 2800)(450 2800);
WIRE 16 -1 (350 2700)(450 2700);
WIRE 16 -1 (350 2600)(450 2600);
WIRE 16 -1 (350 2500)(450 2500);
WIRE 16 -1 (-3850 2400)(-3675 2400);
WIRE 16 -1 (-3850 2450)(-3675 2450);
WIRE 16 -1 (-3850 2250)(-3675 2250);
WIRE 16 -1 (-3850 3050)(-3675 3050);
WIRE 16 -1 (-2475 3400)(-2300 3400);
WIRE 16 -1 (-2475 3350)(-2300 3350);
WIRE 16 -1 (-2475 3300)(-2300 3300);
WIRE 16 -1 (-2475 3250)(-2300 3250);
WIRE 16 -1 (-3675 500)(-4775 500);
FORCEPROP 2 LAST SIG_NAME PD_CHH_CPU1_DIMM2_SAA
J 0
(-4687 509);
DISPLAY 0.680851 (-4687 509);
PAINT WHITE (-4687 509);
WIRE 16 -1 (-3675 400)(-3675 500);
WIRE 16 -1 (-3675 1000)(-4775 1000);
FORCEPROP 2 LAST SIG_NAME M_H_CPU1_SB_RSP<1>
J 0
(-4687 1009);
DISPLAY 0.680851 (-4687 1009);
PAINT WHITE (-4687 1009);
WIRE 16 -1 (-3675 1050)(-4775 1050);
FORCEPROP 2 LAST SIG_NAME M_H_CPU1_SA_RSP<1>
J 0
(-4687 1059);
DISPLAY 0.680851 (-4687 1059);
PAINT WHITE (-4687 1059);
WIRE 16 -1 (-3675 1200)(-4775 1200);
FORCEPROP 2 LAST SIG_NAME TP_CHH_CPU1_DIMM2_FRU_0
J 0
(-4687 1209);
DISPLAY 0.680851 (-4687 1209);
PAINT WHITE (-4687 1209);
WIRE 16 -1 (-3675 1250)(-4775 1250);
FORCEPROP 2 LAST SIG_NAME TP_CHH_CPU1_DIMM2_FRU_1
J 0
(-4687 1259);
DISPLAY 0.680851 (-4687 1259);
PAINT WHITE (-4687 1259);
WIRE 16 -1 (-3850 4350)(-3675 4350);
WIRE 16 -1 (-3675 3150)(-4775 3150);
FORCEPROP 2 LAST SIG_NAME M_H_CPU1_CLK_DN<1>
J 0
(-4687 3159);
DISPLAY 0.680851 (-4687 3159);
PAINT WHITE (-4687 3159);
WIRE 16 -1 (-3675 3200)(-4775 3200);
FORCEPROP 2 LAST SIG_NAME M_H_CPU1_CLK_DP<1>
J 0
(-4687 3209);
DISPLAY 0.680851 (-4687 3209);
PAINT WHITE (-4687 3209);
WIRE 16 -1 (-2475 3700)(-2300 3700);
WIRE 16 -1 (-2475 3750)(-2300 3750);
WIRE 16 -1 (-3850 2500)(-3675 2500);
WIRE 16 -1 (-2475 1800)(-2300 1800);
WIRE 16 -1 (-2475 4300)(-2300 4300);
WIRE 16 -1 (-3675 3350)(-4775 3350);
FORCEPROP 2 LAST SIG_NAME M_H_CPU1_SB_CS_N<3>
J 0
(-4687 3359);
DISPLAY 0.680851 (-4687 3359);
PAINT WHITE (-4687 3359);
WIRE 16 -1 (-2475 2550)(-2300 2550);
WIRE 16 -1 (-2475 2600)(-2300 2600);
WIRE 16 -1 (-3675 3600)(-4775 3600);
FORCEPROP 2 LAST SIG_NAME M_H_CPU1_SB_PAR
J 0
(-4687 3609);
DISPLAY 0.680851 (-4687 3609);
PAINT WHITE (-4687 3609);
WIRE 16 -1 (-3675 3650)(-4775 3650);
FORCEPROP 2 LAST SIG_NAME M_H_CPU1_SA_PAR
J 0
(-4687 3659);
DISPLAY 0.680851 (-4687 3659);
PAINT WHITE (-4687 3659);
WIRE 16 -1 (-2475 1250)(-2300 1250);
WIRE 16 -1 (-2475 1300)(-2300 1300);
WIRE 16 -1 (-2475 1350)(-2300 1350);
WIRE 16 -1 (-2475 1400)(-2300 1400);
WIRE 16 -1 (-2475 1450)(-2300 1450);
WIRE 16 -1 (-2475 1500)(-2300 1500);
WIRE 16 -1 (-2475 1550)(-2300 1550);
WIRE 16 -1 (-2475 1600)(-2300 1600);
WIRE 16 -1 (-2475 1650)(-2300 1650);
WIRE 16 -1 (-2475 1700)(-2300 1700);
WIRE 16 -1 (-2475 1750)(-2300 1750);
WIRE 16 -1 (-2475 1850)(-2300 1850);
WIRE 16 -1 (-2475 1900)(-2300 1900);
WIRE 16 -1 (-2475 1950)(-2300 1950);
WIRE 16 -1 (-2475 2000)(-2300 2000);
WIRE 16 -1 (-2475 2050)(-2300 2050);
WIRE 16 -1 (-2475 2100)(-2300 2100);
WIRE 16 -1 (-2475 2150)(-2300 2150);
WIRE 16 -1 (-2475 2200)(-2300 2200);
WIRE 16 -1 (-2475 2250)(-2300 2250);
WIRE 16 -1 (-2475 2300)(-2300 2300);
WIRE 16 -1 (-2475 2350)(-2300 2350);
WIRE 16 -1 (-2475 2400)(-2300 2400);
WIRE 16 -1 (-2475 2450)(-2300 2450);
WIRE 16 -1 (-2475 2500)(-2300 2500);
WIRE 16 -1 (-2475 2700)(-2300 2700);
WIRE 16 -1 (-2475 2750)(-2300 2750);
WIRE 16 -1 (-2475 2800)(-2300 2800);
WIRE 16 -1 (-2475 2900)(-2300 2900);
WIRE 16 -1 (-2475 3000)(-2300 3000);
WIRE 16 -1 (-2475 3050)(-2300 3050);
WIRE 16 -1 (-2475 3100)(-2300 3100);
WIRE 16 -1 (-2475 3150)(-2300 3150);
WIRE 16 -1 (-2475 3200)(-2300 3200);
WIRE 16 -1 (-2475 3450)(-2300 3450);
WIRE 16 -1 (-2475 3500)(-2300 3500);
WIRE 16 -1 (-2475 3550)(-2300 3550);
WIRE 16 -1 (-2475 3600)(-2300 3600);
WIRE 16 -1 (-2475 3650)(-2300 3650);
WIRE 16 -1 (-2475 3800)(-2300 3800);
WIRE 16 -1 (-2475 3850)(-2300 3850);
WIRE 16 -1 (-2475 3900)(-2300 3900);
WIRE 16 -1 (-2475 3950)(-2300 3950);
WIRE 16 -1 (-2475 4000)(-2300 4000);
WIRE 16 -1 (-2475 4050)(-2300 4050);
WIRE 16 -1 (-2475 4100)(-2300 4100);
WIRE 16 -1 (-2475 4150)(-2300 4150);
WIRE 16 -1 (-2475 4200)(-2300 4200);
WIRE 16 -1 (-2475 4250)(-2300 4250);
WIRE 16 -1 (-2475 4350)(-2300 4350);
WIRE 16 -1 (-2475 4400)(-2300 4400);
WIRE 16 -1 (-3675 3500)(-4775 3500);
FORCEPROP 2 LAST SIG_NAME M_H_CPU1_SA_CS_N<3>
J 0
(-4687 3509);
DISPLAY 0.680851 (-4687 3509);
PAINT WHITE (-4687 3509);
WIRE 16 -1 (-3675 3300)(-4775 3300);
FORCEPROP 2 LAST SIG_NAME M_H_CPU1_SB_CS_N<2>
J 0
(-4687 3309);
DISPLAY 0.680851 (-4687 3309);
PAINT WHITE (-4687 3309);
WIRE 16 -1 (-3675 3450)(-4775 3450);
FORCEPROP 2 LAST SIG_NAME M_H_CPU1_SA_CS_N<2>
J 0
(-4687 3459);
DISPLAY 0.680851 (-4687 3459);
PAINT WHITE (-4687 3459);
WIRE 16 -1 (-3850 2300)(-3675 2300);
WIRE 16 -1 (-3850 2350)(-3675 2350);
WIRE 16 -1 (-3850 2800)(-3675 2800);
WIRE 16 -1 (-3850 2850)(-3675 2850);
WIRE 16 -1 (-3850 3000)(-3675 3000);
WIRE 16 -1 (-3850 4050)(-3675 4050);
WIRE 16 -1 (-3850 4450)(-3675 4450);
WIRE 16 -1 (-3850 4000)(-3675 4000);
WIRE 16 -1 (-3850 4400)(-3675 4400);
WIRE 16 -1 (-3850 3950)(-3675 3950);
WIRE 16 -1 (-3850 3900)(-3675 3900);
WIRE 16 -1 (-3850 4300)(-3675 4300);
WIRE 16 -1 (-3850 3850)(-3675 3850);
WIRE 16 -1 (-3850 4250)(-3675 4250);
WIRE 16 -1 (-3850 3800)(-3675 3800);
WIRE 16 -1 (-3850 4200)(-3675 4200);
WIRE 16 -1 (-3850 3750)(-3675 3750);
WIRE 16 -1 (-3850 4150)(-3675 4150);
WIRE 16 -1 (-3850 2600)(-3675 2600);
WIRE 16 -1 (-3850 2750)(-3675 2750);
WIRE 16 -1 (-3850 2900)(-3675 2900);
WIRE 16 -1 (-2475 4450)(-2300 4450);
DOT 1 (3875 4400);
DOT 1 (3875 4350);
DOT 1 (3875 4300);
DOT 1 (3875 4250);
DOT 1 (3875 4200);
DOT 1 (3875 4150);
DOT 1 (2175 4400);
DOT 1 (2175 4250);
DOT 1 (2175 4150);
DOT 1 (2175 4200);
DOT 1 (3875 4100);
DOT 1 (2175 4100);
DOT 1 (3875 4050);
DOT 1 (3875 4000);
DOT 1 (3875 3950);
DOT 1 (3875 3900);
DOT 1 (3875 3850);
DOT 1 (3875 3800);
DOT 1 (3875 3750);
DOT 1 (3875 3700);
DOT 1 (3875 3650);
DOT 1 (3875 3600);
DOT 1 (3875 3550);
DOT 1 (3875 3400);
DOT 1 (3875 3350);
DOT 1 (3875 3250);
DOT 1 (3875 3300);
DOT 1 (3875 3200);
DOT 1 (3875 3150);
DOT 1 (3875 3100);
DOT 1 (3875 3050);
DOT 1 (3875 3000);
DOT 1 (3875 2950);
DOT 1 (3875 2900);
DOT 1 (3875 2850);
DOT 1 (3875 2800);
DOT 1 (3875 2750);
DOT 1 (3875 2700);
DOT 1 (3875 2600);
DOT 1 (3875 2650);
DOT 1 (3875 2550);
DOT 1 (3875 2500);
DOT 1 (3875 2450);
DOT 1 (3875 2400);
DOT 1 (3875 2350);
DOT 1 (3875 2300);
DOT 1 (3875 2250);
DOT 1 (3875 2200);
DOT 1 (3875 2150);
DOT 1 (3875 2100);
DOT 1 (2175 4000);
DOT 1 (2175 4050);
DOT 1 (2175 3950);
DOT 1 (2175 3900);
DOT 1 (2175 3850);
DOT 1 (2175 3750);
DOT 1 (2175 3800);
DOT 1 (2175 3700);
DOT 1 (2175 3600);
DOT 1 (2175 3650);
DOT 1 (2175 3500);
DOT 1 (2175 3550);
DOT 1 (2175 3450);
DOT 1 (2175 3400);
DOT 1 (2175 3350);
DOT 1 (2175 3250);
DOT 1 (2175 3300);
DOT 1 (2175 3150);
DOT 1 (2175 2900);
DOT 1 (2175 2850);
DOT 1 (2175 2750);
DOT 1 (2175 2800);
DOT 1 (2175 2700);
DOT 1 (2175 2450);
DOT 1 (2175 2500);
DOT 1 (2175 2400);
DOT 1 (2175 2350);
DOT 1 (2175 2200);
DOT 1 (2175 2250);
DOT 1 (2175 2300);
DOT 1 (2175 2150);
DOT 1 (3875 2050);
DOT 1 (3875 2000);
DOT 1 (3875 1950);
DOT 1 (3875 1900);
DOT 1 (3875 1850);
DOT 1 (3875 1800);
DOT 1 (3875 1750);
DOT 1 (3875 1700);
DOT 1 (3875 1650);
DOT 1 (3875 1550);
DOT 1 (3875 1600);
DOT 1 (3875 1500);
DOT 1 (3875 1450);
DOT 1 (3875 1400);
DOT 1 (3875 1350);
DOT 1 (3875 1300);
DOT 1 (2175 1950);
DOT 1 (2175 2000);
DOT 1 (2175 1900);
DOT 1 (2175 1850);
DOT 1 (2175 1800);
DOT 1 (2175 1700);
DOT 1 (2175 1750);
DOT 1 (2175 1650);
DOT 1 (2175 1600);
DOT 1 (2175 1550);
DOT 1 (2175 1450);
DOT 1 (2175 1500);
DOT 1 (2175 1400);
DOT 1 (2175 1350);
DOT 1 (2175 1200);
DOT 1 (2175 1250);
DOT 1 (1100 325);
DOT 1 (475 800);
DOT 1 (3875 3500);
DOT 1 (2175 4450);
DOT 1 (2175 3200);
DOT 1 (2175 3100);
DOT 1 (2175 3050);
DOT 1 (2175 3000);
DOT 1 (2175 2950);
DOT 1 (3875 1200);
DOT 1 (3875 1150);
DOT 1 (3875 1100);
DOT 1 (2175 2650);
DOT 1 (2175 2050);
DOT 1 (2175 2550);
DOT 1 (3875 3450);
DOT 1 (2175 2600);
DOT 1 (2175 2100);
DOT 1 (2175 1300);
FORCENOTE
20210728 MODIFY FOR GT
(-5125 5125) 0;
DISPLAY LEFT (-5125 5125);
DISPLAY 2.510638 (-5125 5125);
PAINT PINK (-5125 5125);
QUIT
